FILE_TYPE = MACRO_DRAWING;
SET COLOR_WIRE YELLOW;
SET COLOR_PROP ORANGE;
SET COLOR_DOT WHITE;
SET COLOR_ARC YELLOW;
SET COLOR_BODY GREEN;
SET COLOR_NOTE PURPLE;
SET PROP_DISPLAY VALUE;
SET PAGE_NUMBER P330;
FORCEADD UNIVERSAL_GND..1
(-6025 3625);
FORCEPROP 3 LASTPIN (-6025 3675) SIG_NAME GND\g
J 0
(-6015 3685);
DISPLAY 0.659574 (-6015 3685);
PAINT MONO (-6015 3685);
DISPLAY INVISIBLE (-6015 3685);
FORCEPROP 2 LAST CDS_LIB pure_quanta_power
J 0
(-6025 3625);
DISPLAY INVISIBLE (-6025 3625);
FORCEPROP 1 LAST HDL_POWER GND
J 1
(-6000 3550);
DISPLAY 0.872340 (-6000 3550);
PAINT GREEN (-6000 3550);
DISPLAY INVISIBLE (-6000 3550);
FORCEPROP 1 LAST PATH I1
J 0
(-5950 3625);
DISPLAY 0.872340 (-5950 3625);
PAINT AQUA (-5950 3625);
DISPLAY INVISIBLE (-5950 3625);
FORCEADD OFFPAGE..4
R 2
(-6850 7775);
FORCEPROP 2 LAST $XR0 122 
J 0
(-7102 7775);
DISPLAY 0.638298 (-7102 7775);
PAINT MONO (-7102 7775);
FORCEPROP 2 LAST CDS_LIB standard
J 0
(-6850 7775);
DISPLAY INVISIBLE (-6850 7775);
FORCEPROP 1 LAST OFFPAGE TRUE
J 2
(-7175 7650);
DISPLAY 0.872340 (-7175 7650);
PAINT GREEN (-7175 7650);
DISPLAY INVISIBLE (-7175 7650);
FORCEPROP 1 LAST COMMENT_BODY TRUE
J 2
(-6825 7675);
DISPLAY 0.872340 (-6825 7675);
PAINT GREEN (-6825 7675);
DISPLAY INVISIBLE (-6825 7675);
FORCEPROP 2 LAST PATH I10
J 0
(-7125 7825);
DISPLAY 0.680851 (-7125 7825);
DISPLAY INVISIBLE (-7125 7825);
FORCEADD UNIVERSAL_GND..1
(-6275 7200);
FORCEPROP 3 LASTPIN (-6275 7250) SIG_NAME GND\g
J 0
(-6265 7260);
DISPLAY 0.659574 (-6265 7260);
PAINT MONO (-6265 7260);
DISPLAY INVISIBLE (-6265 7260);
FORCEPROP 2 LAST CDS_LIB pure_quanta_power
J 0
(-6275 7200);
DISPLAY INVISIBLE (-6275 7200);
FORCEPROP 1 LAST HDL_POWER GND
J 1
(-6250 7125);
DISPLAY 0.872340 (-6250 7125);
PAINT GREEN (-6250 7125);
DISPLAY INVISIBLE (-6250 7125);
FORCEPROP 1 LAST PATH I11
J 0
(-6200 7200);
DISPLAY 0.872340 (-6200 7200);
PAINT AQUA (-6200 7200);
DISPLAY INVISIBLE (-6200 7200);
FORCEADD Q_RES..2
R 2
(-6275 7525);
FORCEPROP 1 LAST LOCATION R8001
J 2
(-6320 7650);
DISPLAY 0.978723 (-6320 7650);
PAINT SKYBLUE (-6320 7650);
FORCEPROP 2 LAST SEC 1
J 0
(-6325 7750);
DISPLAY 0.680851 (-6325 7750);
PAINT MONO (-6325 7750);
DISPLAY INVISIBLE (-6325 7750);
FORCEPROP 1 LASTPIN (-6275 7625) $PN 1
J 2
(-6280 7587);
DISPLAY 0.787234 (-6280 7587);
PAINT MONO (-6280 7587);
FORCEPROP 1 LASTPIN (-6275 7425) $PN 2
J 2
(-6280 7435);
DISPLAY 0.787234 (-6280 7435);
PAINT MONO (-6280 7435);
FORCEPROP 1 LAST WATTAGE 1/16W
J 2
(-6315 7500);
DISPLAY 0.978723 (-6315 7500);
PAINT SKYBLUE (-6315 7500);
FORCEPROP 1 LAST MATERIAL EMPTY
J 2
(-6315 7450);
DISPLAY 0.978723 (-6315 7450);
PAINT SKYBLUE (-6315 7450);
FORCEPROP 1 LAST VALUE 100K
J 2
(-6320 7600);
DISPLAY 0.978723 (-6320 7600);
PAINT SKYBLUE (-6320 7600);
FORCEPROP 1 LAST TOLERANCE 1%
J 2
(-6320 7550);
DISPLAY 0.978723 (-6320 7550);
PAINT SKYBLUE (-6320 7550);
FORCEPROP 1 LAST PACK_TYPE 0402LF
J 2
(-6315 7350);
DISPLAY 0.978723 (-6315 7350);
PAINT SKYBLUE (-6315 7350);
FORCEPROP 2 LAST SEC_TYPE 0402LF
J 0
(-6325 7750);
DISPLAY 0.680851 (-6325 7750);
DISPLAY INVISIBLE (-6325 7750);
FORCEPROP 2 LAST CDS_LIB pure_quanta
J 2
(-6275 7525);
DISPLAY INVISIBLE (-6275 7525);
FORCEPROP 1 LAST PATH I12
J 2
(-6325 7700);
DISPLAY 0.978723 (-6325 7700);
PAINT WHITE (-6325 7700);
DISPLAY INVISIBLE (-6325 7700);
FORCEPROP 1 LAST PART_NUMBER CS41002FB09
J 2
(-6315 7400);
DISPLAY 0.978723 (-6315 7400);
PAINT SKYBLUE (-6315 7400);
DISPLAY INVISIBLE (-6315 7400);
FORCEADD Q_RES..2
R 2
(-6300 8150);
FORCEPROP 1 LAST LOCATION R4058
J 2
(-6345 8275);
DISPLAY 0.808511 (-6345 8275);
FORCEPROP 2 LAST SEC 1
J 0
(-6350 8375);
DISPLAY 0.680851 (-6350 8375);
PAINT MONO (-6350 8375);
DISPLAY INVISIBLE (-6350 8375);
FORCEPROP 1 LASTPIN (-6300 8250) $PN 1
J 2
(-6305 8212);
DISPLAY 0.787234 (-6305 8212);
PAINT MONO (-6305 8212);
FORCEPROP 1 LASTPIN (-6300 8050) $PN 2
J 2
(-6305 8060);
DISPLAY 0.787234 (-6305 8060);
PAINT MONO (-6305 8060);
FORCEPROP 1 LAST TOLERANCE 1%
J 2
(-6345 8175);
DISPLAY 0.638298 (-6345 8175);
FORCEPROP 1 LAST PACK_TYPE 0402LF
J 2
(-6340 7975);
DISPLAY 0.638298 (-6340 7975);
FORCEPROP 1 LAST WATTAGE 1/16W
J 2
(-6340 8125);
DISPLAY 0.638298 (-6340 8125);
FORCEPROP 1 LAST MATERIAL CHIP
J 2
(-6340 8075);
DISPLAY 0.638298 (-6340 8075);
FORCEPROP 1 LAST VALUE 10K
J 2
(-6345 8225);
DISPLAY 0.638298 (-6345 8225);
FORCEPROP 2 LAST SEC_TYPE 0402LF
J 0
(-6350 8375);
DISPLAY 0.680851 (-6350 8375);
DISPLAY INVISIBLE (-6350 8375);
FORCEPROP 2 LAST CDS_LIB pure_quanta
J 2
(-6300 8150);
DISPLAY INVISIBLE (-6300 8150);
FORCEPROP 1 LAST PATH I13
J 2
(-6350 8325);
DISPLAY 0.978723 (-6350 8325);
PAINT WHITE (-6350 8325);
DISPLAY INVISIBLE (-6350 8325);
FORCEPROP 1 LAST PART_NUMBER CS31002FB08
J 2
(-6340 8025);
DISPLAY 0.638298 (-6340 8025);
DISPLAY INVISIBLE (-6340 8025);
FORCEADD UNIVERSAL_GND..1
(-6075 5425);
FORCEPROP 3 LASTPIN (-6075 5475) SIG_NAME GND\g
J 0
(-6065 5485);
DISPLAY 0.659574 (-6065 5485);
PAINT MONO (-6065 5485);
DISPLAY INVISIBLE (-6065 5485);
FORCEPROP 2 LAST CDS_LIB pure_quanta_power
J 0
(-6075 5425);
DISPLAY INVISIBLE (-6075 5425);
FORCEPROP 1 LAST HDL_POWER GND
J 1
(-6050 5350);
DISPLAY 0.872340 (-6050 5350);
PAINT GREEN (-6050 5350);
DISPLAY INVISIBLE (-6050 5350);
FORCEPROP 1 LAST PATH I14
J 0
(-6000 5425);
DISPLAY 0.872340 (-6000 5425);
PAINT AQUA (-6000 5425);
DISPLAY INVISIBLE (-6000 5425);
FORCEADD Q_RES..2
R 2
(-6050 4575);
FORCEPROP 1 LAST LOCATION R9006
J 2
(-6095 4700);
DISPLAY 0.808511 (-6095 4700);
FORCEPROP 0 LAST $SEC 1
J 0
(-6075 4750);
DISPLAY 0.680851 (-6075 4750);
PAINT MONO (-6075 4750);
DISPLAY INVISIBLE (-6075 4750);
FORCEPROP 0 LAST CDS_SEC 1
J 0
(-6075 4750);
DISPLAY 0.680851 (-6075 4750);
DISPLAY INVISIBLE (-6075 4750);
FORCEPROP 1 LASTPIN (-6050 4675) $PN 1
J 2
(-6055 4637);
DISPLAY 0.787234 (-6055 4637);
PAINT MONO (-6055 4637);
FORCEPROP 1 LASTPIN (-6050 4475) $PN 2
J 2
(-6055 4485);
DISPLAY 0.787234 (-6055 4485);
PAINT MONO (-6055 4485);
FORCEPROP 1 LAST MATERIAL CHIP
J 2
(-6090 4500);
DISPLAY 0.638298 (-6090 4500);
FORCEPROP 1 LAST VALUE 10K
J 2
(-6095 4650);
DISPLAY 0.638298 (-6095 4650);
FORCEPROP 1 LAST WATTAGE 1/16W
J 2
(-6090 4550);
DISPLAY 0.638298 (-6090 4550);
FORCEPROP 1 LAST PACK_TYPE 0402LF
J 2
(-6090 4400);
DISPLAY 0.638298 (-6090 4400);
FORCEPROP 1 LAST TOLERANCE 1%
J 2
(-6095 4600);
DISPLAY 0.638298 (-6095 4600);
FORCEPROP 2 LAST CDS_LIB pure_quanta
J 0
(-6050 4575);
DISPLAY INVISIBLE (-6050 4575);
FORCEPROP 1 LAST PATH I15
J 2
(-6100 4750);
DISPLAY 0.978723 (-6100 4750);
PAINT WHITE (-6100 4750);
DISPLAY INVISIBLE (-6100 4750);
FORCEPROP 1 LAST PART_NUMBER CS31002FB08
J 2
(-6090 4450);
DISPLAY 0.638298 (-6090 4450);
DISPLAY INVISIBLE (-6090 4450);
FORCEADD UNIVERSAL_POWER..1
(-6050 4875);
FORCEPROP 3 LASTPIN (-6050 4825) SIG_NAME P3V3_AUX\g
J 0
(-6040 4835);
DISPLAY 0.659574 (-6040 4835);
PAINT MONO (-6040 4835);
DISPLAY INVISIBLE (-6040 4835);
FORCEPROP 1 LAST HDL_POWER P3V3_AUX
J 1
(-6050 4925);
DISPLAY 0.872340 (-6050 4925);
PAINT GREEN (-6050 4925);
FORCEPROP 2 LAST CDS_LIB pure_quanta_power
J 0
(-6050 4875);
DISPLAY INVISIBLE (-6050 4875);
FORCEPROP 1 LAST PATH I16
J 0
(-6000 4900);
DISPLAY 0.872340 (-6000 4900);
PAINT AQUA (-6000 4900);
DISPLAY INVISIBLE (-6000 4900);
FORCEADD Q_RES..2
R 2
(-5650 4900);
FORCEPROP 1 LAST LOCATION R9008
J 2
(-5695 5025);
DISPLAY 0.638298 (-5695 5025);
PAINT SKYBLUE (-5695 5025);
FORCEPROP 0 LAST $SEC 1
J 0
(-5675 5075);
DISPLAY 0.680851 (-5675 5075);
PAINT MONO (-5675 5075);
DISPLAY INVISIBLE (-5675 5075);
FORCEPROP 0 LAST CDS_SEC 1
J 0
(-5675 5075);
DISPLAY 0.680851 (-5675 5075);
DISPLAY INVISIBLE (-5675 5075);
FORCEPROP 1 LASTPIN (-5650 5000) $PN 1
J 2
(-5655 4962);
DISPLAY 0.787234 (-5655 4962);
PAINT MONO (-5655 4962);
FORCEPROP 1 LASTPIN (-5650 4800) $PN 2
J 2
(-5655 4810);
DISPLAY 0.787234 (-5655 4810);
PAINT MONO (-5655 4810);
FORCEPROP 1 LAST PACK_TYPE 0402LF
J 2
(-5690 4725);
DISPLAY 0.638298 (-5690 4725);
PAINT SKYBLUE (-5690 4725);
FORCEPROP 1 LAST VALUE 4.7K
J 2
(-5695 4975);
DISPLAY 0.638298 (-5695 4975);
PAINT SKYBLUE (-5695 4975);
FORCEPROP 1 LAST MATERIAL CHIP
J 2
(-5690 4825);
DISPLAY 0.638298 (-5690 4825);
PAINT SKYBLUE (-5690 4825);
FORCEPROP 1 LAST WATTAGE 1/16W
J 2
(-5690 4875);
DISPLAY 0.638298 (-5690 4875);
PAINT SKYBLUE (-5690 4875);
FORCEPROP 1 LAST TOLERANCE 5%
J 2
(-5695 4925);
DISPLAY 0.638298 (-5695 4925);
PAINT SKYBLUE (-5695 4925);
FORCEPROP 2 LAST CDS_LIB pure_quanta
J 0
(-5650 4900);
DISPLAY INVISIBLE (-5650 4900);
FORCEPROP 1 LAST PATH I17
J 2
(-5700 5075);
DISPLAY 0.978723 (-5700 5075);
PAINT WHITE (-5700 5075);
DISPLAY INVISIBLE (-5700 5075);
FORCEPROP 1 LAST PART_NUMBER CS24702JB10
J 2
(-5690 4775);
DISPLAY 0.638298 (-5690 4775);
PAINT SKYBLUE (-5690 4775);
DISPLAY INVISIBLE (-5690 4775);
FORCEADD UNIVERSAL_POWER..1
(-5650 5250);
FORCEPROP 3 LASTPIN (-5650 5200) SIG_NAME P3V3_AUX\g
J 0
(-5640 5210);
DISPLAY 0.659574 (-5640 5210);
PAINT MONO (-5640 5210);
DISPLAY INVISIBLE (-5640 5210);
FORCEPROP 1 LAST HDL_POWER P3V3_AUX
J 1
(-5650 5300);
DISPLAY 0.872340 (-5650 5300);
PAINT GREEN (-5650 5300);
FORCEPROP 2 LAST CDS_LIB pure_quanta_power
J 0
(-5650 5250);
DISPLAY INVISIBLE (-5650 5250);
FORCEPROP 1 LAST PATH I18
J 0
(-5600 5275);
DISPLAY 0.872340 (-5600 5275);
PAINT AQUA (-5600 5275);
DISPLAY INVISIBLE (-5600 5275);
FORCEADD UNIVERSAL_GND..1
(-5700 5500);
FORCEPROP 3 LASTPIN (-5700 5550) SIG_NAME GND\g
J 0
(-5690 5560);
DISPLAY 0.659574 (-5690 5560);
PAINT MONO (-5690 5560);
DISPLAY INVISIBLE (-5690 5560);
FORCEPROP 2 LAST CDS_LIB pure_quanta_power
J 0
(-5700 5500);
DISPLAY INVISIBLE (-5700 5500);
FORCEPROP 1 LAST HDL_POWER GND
J 1
(-5675 5425);
DISPLAY 0.872340 (-5675 5425);
PAINT GREEN (-5675 5425);
DISPLAY INVISIBLE (-5675 5425);
FORCEPROP 1 LAST PATH I19
J 0
(-5625 5500);
DISPLAY 0.872340 (-5625 5500);
PAINT AQUA (-5625 5500);
DISPLAY INVISIBLE (-5625 5500);
FORCEADD Q_RES..2
R 2
(-6025 3950);
FORCEPROP 1 LAST LOCATION R9007
J 2
(-6070 4075);
DISPLAY 0.978723 (-6070 4075);
PAINT SKYBLUE (-6070 4075);
FORCEPROP 0 LAST $SEC 1
J 0
(-6050 4125);
DISPLAY 0.680851 (-6050 4125);
PAINT MONO (-6050 4125);
DISPLAY INVISIBLE (-6050 4125);
FORCEPROP 0 LAST CDS_SEC 1
J 0
(-6050 4125);
DISPLAY 0.680851 (-6050 4125);
DISPLAY INVISIBLE (-6050 4125);
FORCEPROP 1 LASTPIN (-6025 4050) $PN 1
J 2
(-6030 4012);
DISPLAY 0.787234 (-6030 4012);
PAINT MONO (-6030 4012);
FORCEPROP 1 LASTPIN (-6025 3850) $PN 2
J 2
(-6030 3860);
DISPLAY 0.787234 (-6030 3860);
PAINT MONO (-6030 3860);
FORCEPROP 1 LAST MATERIAL EMPTY
J 2
(-6065 3875);
DISPLAY 0.978723 (-6065 3875);
PAINT SKYBLUE (-6065 3875);
FORCEPROP 1 LAST PACK_TYPE 0402LF
J 2
(-6065 3775);
DISPLAY 0.978723 (-6065 3775);
PAINT SKYBLUE (-6065 3775);
FORCEPROP 1 LAST VALUE 100K
J 2
(-6070 4025);
DISPLAY 0.978723 (-6070 4025);
PAINT SKYBLUE (-6070 4025);
FORCEPROP 1 LAST WATTAGE 1/16W
J 2
(-6065 3925);
DISPLAY 0.978723 (-6065 3925);
PAINT SKYBLUE (-6065 3925);
FORCEPROP 1 LAST TOLERANCE 1%
J 2
(-6070 3975);
DISPLAY 0.978723 (-6070 3975);
PAINT SKYBLUE (-6070 3975);
FORCEPROP 2 LAST CDS_LIB pure_quanta
J 0
(-6025 3950);
DISPLAY INVISIBLE (-6025 3950);
FORCEPROP 1 LAST PATH I2
J 2
(-6075 4125);
DISPLAY 0.978723 (-6075 4125);
PAINT WHITE (-6075 4125);
DISPLAY INVISIBLE (-6075 4125);
FORCEPROP 1 LAST PART_NUMBER CS41002FB09
J 2
(-6065 3825);
DISPLAY 0.978723 (-6065 3825);
PAINT SKYBLUE (-6065 3825);
DISPLAY INVISIBLE (-6065 3825);
FORCEADD Q_RES..2
R 2
(-6075 5750);
FORCEPROP 1 LAST LOCATION R9003
J 2
(-6120 5875);
DISPLAY 0.978723 (-6120 5875);
PAINT SKYBLUE (-6120 5875);
FORCEPROP 2 LAST SEC 1
J 0
(-6125 5975);
DISPLAY 0.680851 (-6125 5975);
PAINT MONO (-6125 5975);
DISPLAY INVISIBLE (-6125 5975);
FORCEPROP 1 LASTPIN (-6075 5850) $PN 1
J 2
(-6080 5812);
DISPLAY 0.787234 (-6080 5812);
PAINT MONO (-6080 5812);
FORCEPROP 1 LASTPIN (-6075 5650) $PN 2
J 2
(-6080 5660);
DISPLAY 0.787234 (-6080 5660);
PAINT MONO (-6080 5660);
FORCEPROP 1 LAST VALUE 100K
J 2
(-6120 5825);
DISPLAY 0.978723 (-6120 5825);
PAINT SKYBLUE (-6120 5825);
FORCEPROP 1 LAST TOLERANCE 1%
J 2
(-6120 5775);
DISPLAY 0.978723 (-6120 5775);
PAINT SKYBLUE (-6120 5775);
FORCEPROP 1 LAST WATTAGE 1/16W
J 2
(-6115 5725);
DISPLAY 0.978723 (-6115 5725);
PAINT SKYBLUE (-6115 5725);
FORCEPROP 1 LAST MATERIAL EMPTY
J 2
(-6115 5675);
DISPLAY 0.978723 (-6115 5675);
PAINT SKYBLUE (-6115 5675);
FORCEPROP 1 LAST PACK_TYPE 0402LF
J 2
(-6115 5575);
DISPLAY 0.978723 (-6115 5575);
PAINT SKYBLUE (-6115 5575);
FORCEPROP 2 LAST SEC_TYPE 0402LF
J 0
(-6125 5975);
DISPLAY 0.680851 (-6125 5975);
DISPLAY INVISIBLE (-6125 5975);
FORCEPROP 2 LAST CDS_LIB pure_quanta
J 2
(-6075 5750);
DISPLAY INVISIBLE (-6075 5750);
FORCEPROP 1 LAST PATH I20
J 2
(-6125 5925);
DISPLAY 0.978723 (-6125 5925);
PAINT WHITE (-6125 5925);
DISPLAY INVISIBLE (-6125 5925);
FORCEPROP 1 LAST PART_NUMBER CS41002FB09
J 2
(-6115 5625);
DISPLAY 0.978723 (-6115 5625);
PAINT SKYBLUE (-6115 5625);
DISPLAY INVISIBLE (-6115 5625);
FORCEADD MOSFET_NCH_DUAL..1
(-5750 6050);
FORCEPROP 1 LAST LOCATION Q9000
J 0
(-5599 6024);
DISPLAY 0.723404 (-5599 6024);
PAINT SKYBLUE (-5599 6024);
FORCEPROP 2 LAST SEC 1
J 0
(-5575 6175);
DISPLAY 0.680851 (-5575 6175);
PAINT MONO (-5575 6175);
DISPLAY INVISIBLE (-5575 6175);
FORCEPROP 2 LASTPIN (-5700 6250) $PN 6
R 1
J 0
(-5710 6260);
DISPLAY 0.680851 (-5710 6260);
PAINT MONO (-5710 6260);
FORCEPROP 2 LASTPIN (-5950 6000) $PN 2
J 2
(-5960 6010);
DISPLAY 0.680851 (-5960 6010);
PAINT MONO (-5960 6010);
FORCEPROP 2 LASTPIN (-5700 5850) $PN 1
R 1
J 2
(-5710 5840);
DISPLAY 0.680851 (-5710 5840);
PAINT MONO (-5710 5840);
FORCEPROP 2 LAST PART_TYPE SMLF
J 0
(-5575 6125);
DISPLAY 0.680851 (-5575 6125);
PAINT SKYBLUE (-5575 6125);
FORCEPROP 2 LAST VALUE PJT138K
J 0
(-5575 6075);
DISPLAY 0.680851 (-5575 6075);
PAINT SKYBLUE (-5575 6075);
FORCEPROP 1 LAST MATERIAL IC
J 0
(-5599 5899);
DISPLAY 0.723404 (-5599 5899);
PAINT SKYBLUE (-5599 5899);
FORCEPROP 1 LAST NEEDS_NO_SIZE TRUE
J 0
(-5750 6049);
DISPLAY 0.468085 (-5750 6049);
PAINT GREEN (-5750 6049);
DISPLAY INVISIBLE (-5750 6049);
FORCEPROP 2 LAST SEC_TYPE 
J 0
(-5575 6175);
DISPLAY 0.680851 (-5575 6175);
DISPLAY INVISIBLE (-5575 6175);
FORCEPROP 2 LAST CDS_LIB pure_quanta
J 0
(-5750 6050);
DISPLAY INVISIBLE (-5750 6050);
FORCEPROP 1 LAST CDS_LMAN_SYM_OUTLINE -150,150,150,-150
J 0
(-5750 6050);
DISPLAY 0.468085 (-5750 6050);
PAINT GREEN (-5750 6050);
DISPLAY INVISIBLE (-5750 6050);
FORCEPROP 1 LAST PATH I21
J 0
(-5750 6050);
DISPLAY 0.723404 (-5750 6050);
PAINT GREEN (-5750 6050);
DISPLAY INVISIBLE (-5750 6050);
FORCEPROP 1 LAST PART_NUMBER BAM138K0003
J 0
(-5599 5964);
DISPLAY 0.723404 (-5599 5964);
PAINT SKYBLUE (-5599 5964);
DISPLAY INVISIBLE (-5599 5964);
FORCEADD MOSFET_NCH_DUAL..2
(-4700 4600);
FORCEPROP 1 LAST LOCATION Q9001
J 0
(-4549 4576);
DISPLAY 0.723404 (-4549 4576);
PAINT SKYBLUE (-4549 4576);
FORCEPROP 0 LAST $SEC 2
J 0
(-4525 4725);
DISPLAY 0.680851 (-4525 4725);
PAINT MONO (-4525 4725);
DISPLAY INVISIBLE (-4525 4725);
FORCEPROP 0 LAST CDS_SEC 2
J 0
(-4525 4725);
DISPLAY 0.680851 (-4525 4725);
DISPLAY INVISIBLE (-4525 4725);
FORCEPROP 0 LASTPIN (-4650 4800) $PN 3
R 1
J 0
(-4660 4810);
DISPLAY 0.680851 (-4660 4810);
PAINT MONO (-4660 4810);
FORCEPROP 0 LASTPIN (-4900 4550) $PN 5
J 2
(-4910 4560);
DISPLAY 0.680851 (-4910 4560);
PAINT MONO (-4910 4560);
FORCEPROP 0 LASTPIN (-4650 4400) $PN 4
R 1
J 2
(-4660 4390);
DISPLAY 0.680851 (-4660 4390);
PAINT MONO (-4660 4390);
FORCEPROP 2 LAST PART_TYPE SMLF
J 0
(-4525 4675);
DISPLAY 0.680851 (-4525 4675);
PAINT SKYBLUE (-4525 4675);
FORCEPROP 2 LAST VALUE PJT138K
J 0
(-4525 4625);
DISPLAY 0.680851 (-4525 4625);
PAINT SKYBLUE (-4525 4625);
FORCEPROP 1 LAST MATERIAL IC
J 0
(-4549 4451);
DISPLAY 0.723404 (-4549 4451);
PAINT SKYBLUE (-4549 4451);
FORCEPROP 1 LAST NEEDS_NO_SIZE TRUE
J 0
(-4550 4491);
DISPLAY 0.468085 (-4550 4491);
PAINT GREEN (-4550 4491);
DISPLAY INVISIBLE (-4550 4491);
FORCEPROP 1 LAST CDS_LMAN_SYM_OUTLINE -150,150,150,-150
J 0
(-4700 4600);
DISPLAY 0.468085 (-4700 4600);
PAINT GREEN (-4700 4600);
DISPLAY INVISIBLE (-4700 4600);
FORCEPROP 2 LAST CDS_LIB pure_quanta
J 0
(-4700 4600);
DISPLAY INVISIBLE (-4700 4600);
FORCEPROP 1 LAST PATH I22
J 0
(-4550 4450);
DISPLAY 0.723404 (-4550 4450);
PAINT GREEN (-4550 4450);
DISPLAY INVISIBLE (-4550 4450);
FORCEPROP 1 LAST PART_NUMBER BAM138K0003
J 0
(-4549 4506);
DISPLAY 0.723404 (-4549 4506);
PAINT SKYBLUE (-4549 4506);
DISPLAY INVISIBLE (-4549 4506);
FORCEADD Q_RES..2
R 2
(-4650 5150);
FORCEPROP 1 LAST LOCATION R9009
J 2
(-4695 5275);
DISPLAY 0.978723 (-4695 5275);
PAINT SKYBLUE (-4695 5275);
FORCEPROP 0 LAST $SEC 1
J 0
(-4675 5325);
DISPLAY 0.680851 (-4675 5325);
PAINT MONO (-4675 5325);
DISPLAY INVISIBLE (-4675 5325);
FORCEPROP 0 LAST CDS_SEC 1
J 0
(-4675 5325);
DISPLAY 0.680851 (-4675 5325);
DISPLAY INVISIBLE (-4675 5325);
FORCEPROP 1 LASTPIN (-4650 5250) $PN 1
J 2
(-4655 5212);
DISPLAY 0.787234 (-4655 5212);
PAINT MONO (-4655 5212);
FORCEPROP 1 LASTPIN (-4650 5050) $PN 2
J 2
(-4655 5060);
DISPLAY 0.787234 (-4655 5060);
PAINT MONO (-4655 5060);
FORCEPROP 1 LAST TOLERANCE 5%
J 2
(-4695 5175);
DISPLAY 0.638298 (-4695 5175);
PAINT SKYBLUE (-4695 5175);
FORCEPROP 1 LAST VALUE 4.7K
J 2
(-4695 5225);
DISPLAY 0.638298 (-4695 5225);
PAINT SKYBLUE (-4695 5225);
FORCEPROP 1 LAST MATERIAL CHIP
J 2
(-4690 5075);
DISPLAY 0.638298 (-4690 5075);
PAINT SKYBLUE (-4690 5075);
FORCEPROP 1 LAST WATTAGE 1/16W
J 2
(-4690 5125);
DISPLAY 0.638298 (-4690 5125);
PAINT SKYBLUE (-4690 5125);
FORCEPROP 1 LAST PACK_TYPE 0402LF
J 2
(-4690 4975);
DISPLAY 0.638298 (-4690 4975);
PAINT SKYBLUE (-4690 4975);
FORCEPROP 2 LAST CDS_LIB pure_quanta
J 0
(-4650 5150);
DISPLAY INVISIBLE (-4650 5150);
FORCEPROP 1 LAST PATH I23
J 2
(-4700 5325);
DISPLAY 0.978723 (-4700 5325);
PAINT WHITE (-4700 5325);
DISPLAY INVISIBLE (-4700 5325);
FORCEPROP 1 LAST PART_NUMBER CS24702JB10
J 2
(-4690 5025);
DISPLAY 0.638298 (-4690 5025);
PAINT SKYBLUE (-4690 5025);
DISPLAY INVISIBLE (-4690 5025);
FORCEADD UNIVERSAL_POWER..1
(-4650 5425);
FORCEPROP 3 LASTPIN (-4650 5375) SIG_NAME P3V3_AUX\g
J 0
(-4640 5385);
DISPLAY 0.659574 (-4640 5385);
PAINT MONO (-4640 5385);
DISPLAY INVISIBLE (-4640 5385);
FORCEPROP 1 LAST HDL_POWER P3V3_AUX
J 1
(-4650 5475);
DISPLAY 0.872340 (-4650 5475);
PAINT GREEN (-4650 5475);
FORCEPROP 2 LAST CDS_LIB pure_quanta_power
J 0
(-4650 5425);
DISPLAY INVISIBLE (-4650 5425);
FORCEPROP 1 LAST PATH I24
J 0
(-4600 5450);
DISPLAY 0.872340 (-4600 5450);
PAINT AQUA (-4600 5450);
DISPLAY INVISIBLE (-4600 5450);
FORCEADD UNIVERSAL_GND..1
(-4700 5875);
FORCEPROP 3 LASTPIN (-4700 5925) SIG_NAME GND\g
J 0
(-4690 5935);
DISPLAY 0.659574 (-4690 5935);
PAINT MONO (-4690 5935);
DISPLAY INVISIBLE (-4690 5935);
FORCEPROP 2 LAST CDS_LIB pure_quanta_power
J 0
(-4700 5875);
DISPLAY INVISIBLE (-4700 5875);
FORCEPROP 1 LAST HDL_POWER GND
J 1
(-4675 5800);
DISPLAY 0.872340 (-4675 5800);
PAINT GREEN (-4675 5800);
DISPLAY INVISIBLE (-4675 5800);
FORCEPROP 1 LAST PATH I25
J 0
(-4625 5875);
DISPLAY 0.872340 (-4625 5875);
PAINT AQUA (-4625 5875);
DISPLAY INVISIBLE (-4625 5875);
FORCEADD Q_RES..2
R 2
(-5700 6700);
FORCEPROP 1 LAST LOCATION R9004
J 2
(-5745 6825);
DISPLAY 0.638298 (-5745 6825);
PAINT SKYBLUE (-5745 6825);
FORCEPROP 0 LAST $SEC 1
J 0
(-5725 6875);
DISPLAY 0.680851 (-5725 6875);
PAINT MONO (-5725 6875);
DISPLAY INVISIBLE (-5725 6875);
FORCEPROP 0 LAST CDS_SEC 1
J 0
(-5725 6875);
DISPLAY 0.680851 (-5725 6875);
DISPLAY INVISIBLE (-5725 6875);
FORCEPROP 1 LASTPIN (-5700 6800) $PN 1
J 2
(-5705 6762);
DISPLAY 0.787234 (-5705 6762);
PAINT MONO (-5705 6762);
FORCEPROP 1 LASTPIN (-5700 6600) $PN 2
J 2
(-5705 6610);
DISPLAY 0.787234 (-5705 6610);
PAINT MONO (-5705 6610);
FORCEPROP 1 LAST PACK_TYPE 0402LF
J 2
(-5740 6525);
DISPLAY 0.638298 (-5740 6525);
PAINT SKYBLUE (-5740 6525);
FORCEPROP 1 LAST MATERIAL CHIP
J 2
(-5740 6625);
DISPLAY 0.638298 (-5740 6625);
PAINT SKYBLUE (-5740 6625);
FORCEPROP 1 LAST WATTAGE 1/16W
J 2
(-5740 6675);
DISPLAY 0.638298 (-5740 6675);
PAINT SKYBLUE (-5740 6675);
FORCEPROP 1 LAST TOLERANCE 5%
J 2
(-5745 6725);
DISPLAY 0.638298 (-5745 6725);
PAINT SKYBLUE (-5745 6725);
FORCEPROP 1 LAST VALUE 4.7K
J 2
(-5745 6775);
DISPLAY 0.638298 (-5745 6775);
PAINT SKYBLUE (-5745 6775);
FORCEPROP 2 LAST CDS_LIB pure_quanta
J 2
(-5700 6700);
DISPLAY INVISIBLE (-5700 6700);
FORCEPROP 1 LAST PATH I26
J 2
(-5750 6875);
DISPLAY 0.978723 (-5750 6875);
PAINT WHITE (-5750 6875);
DISPLAY INVISIBLE (-5750 6875);
FORCEPROP 1 LAST PART_NUMBER CS24702JB10
J 2
(-5740 6575);
DISPLAY 0.638298 (-5740 6575);
PAINT SKYBLUE (-5740 6575);
DISPLAY INVISIBLE (-5740 6575);
FORCEADD UNIVERSAL_POWER..1
(-5700 7050);
FORCEPROP 3 LASTPIN (-5700 7000) SIG_NAME P3V3_AUX\g
J 0
(-5690 7010);
DISPLAY 0.659574 (-5690 7010);
PAINT MONO (-5690 7010);
DISPLAY INVISIBLE (-5690 7010);
FORCEPROP 1 LAST HDL_POWER P3V3_AUX
J 1
(-5700 7100);
DISPLAY 0.872340 (-5700 7100);
PAINT GREEN (-5700 7100);
FORCEPROP 2 LAST CDS_LIB pure_quanta_power
J 0
(-5700 7050);
DISPLAY INVISIBLE (-5700 7050);
FORCEPROP 1 LAST PATH I27
J 0
(-5650 7075);
DISPLAY 0.872340 (-5650 7075);
PAINT AQUA (-5650 7075);
DISPLAY INVISIBLE (-5650 7075);
FORCEADD UNIVERSAL_GND..1
(-5675 7275);
FORCEPROP 3 LASTPIN (-5675 7325) SIG_NAME GND\g
J 0
(-5665 7335);
DISPLAY 0.659574 (-5665 7335);
PAINT MONO (-5665 7335);
DISPLAY INVISIBLE (-5665 7335);
FORCEPROP 2 LAST CDS_LIB pure_quanta_power
J 0
(-5675 7275);
DISPLAY INVISIBLE (-5675 7275);
FORCEPROP 1 LAST HDL_POWER GND
J 1
(-5650 7200);
DISPLAY 0.872340 (-5650 7200);
PAINT GREEN (-5650 7200);
DISPLAY INVISIBLE (-5650 7200);
FORCEPROP 1 LAST PATH I28
J 0
(-5600 7275);
DISPLAY 0.872340 (-5600 7275);
PAINT AQUA (-5600 7275);
DISPLAY INVISIBLE (-5600 7275);
FORCEADD MOSFET_NCH_DUAL..1
(-5725 7825);
FORCEPROP 1 LAST LOCATION Q8000
J 0
(-5574 7799);
DISPLAY 0.723404 (-5574 7799);
PAINT SKYBLUE (-5574 7799);
FORCEPROP 2 LAST SEC 1
J 0
(-5550 7950);
DISPLAY 0.680851 (-5550 7950);
PAINT MONO (-5550 7950);
DISPLAY INVISIBLE (-5550 7950);
FORCEPROP 2 LASTPIN (-5675 8025) $PN 6
R 1
J 0
(-5685 8035);
DISPLAY 0.680851 (-5685 8035);
PAINT MONO (-5685 8035);
FORCEPROP 2 LASTPIN (-5925 7775) $PN 2
J 2
(-5935 7785);
DISPLAY 0.680851 (-5935 7785);
PAINT MONO (-5935 7785);
FORCEPROP 2 LASTPIN (-5675 7625) $PN 1
R 1
J 2
(-5685 7615);
DISPLAY 0.680851 (-5685 7615);
PAINT MONO (-5685 7615);
FORCEPROP 1 LAST MATERIAL IC
J 0
(-5574 7674);
DISPLAY 0.723404 (-5574 7674);
PAINT SKYBLUE (-5574 7674);
FORCEPROP 2 LAST VALUE PJT138K
J 0
(-5550 7850);
DISPLAY 0.680851 (-5550 7850);
PAINT SKYBLUE (-5550 7850);
FORCEPROP 2 LAST PART_TYPE SMLF
J 0
(-5550 7900);
DISPLAY 0.680851 (-5550 7900);
PAINT SKYBLUE (-5550 7900);
FORCEPROP 1 LAST CDS_LMAN_SYM_OUTLINE -150,150,150,-150
J 0
(-5725 7825);
DISPLAY 0.468085 (-5725 7825);
PAINT GREEN (-5725 7825);
DISPLAY INVISIBLE (-5725 7825);
FORCEPROP 1 LAST NEEDS_NO_SIZE TRUE
J 0
(-5725 7824);
DISPLAY 0.468085 (-5725 7824);
PAINT GREEN (-5725 7824);
DISPLAY INVISIBLE (-5725 7824);
FORCEPROP 2 LAST CDS_LIB pure_quanta
J 0
(-5725 7825);
DISPLAY INVISIBLE (-5725 7825);
FORCEPROP 2 LAST SEC_TYPE 
J 0
(-5550 7950);
DISPLAY 0.680851 (-5550 7950);
DISPLAY INVISIBLE (-5550 7950);
FORCEPROP 1 LAST PATH I29
J 0
(-5725 7825);
DISPLAY 0.723404 (-5725 7825);
PAINT GREEN (-5725 7825);
DISPLAY INVISIBLE (-5725 7825);
FORCEPROP 1 LAST PART_NUMBER BAM138K0003
J 0
(-5574 7739);
DISPLAY 0.723404 (-5574 7739);
PAINT SKYBLUE (-5574 7739);
DISPLAY INVISIBLE (-5574 7739);
FORCEADD MOSFET_NCH_DUAL..1
(-5700 4250);
FORCEPROP 1 LAST LOCATION Q9001
J 0
(-5549 4224);
DISPLAY 0.723404 (-5549 4224);
PAINT SKYBLUE (-5549 4224);
FORCEPROP 0 LAST $SEC 1
J 0
(-5525 4375);
DISPLAY 0.680851 (-5525 4375);
PAINT MONO (-5525 4375);
DISPLAY INVISIBLE (-5525 4375);
FORCEPROP 0 LAST CDS_SEC 1
J 0
(-5525 4375);
DISPLAY 0.680851 (-5525 4375);
DISPLAY INVISIBLE (-5525 4375);
FORCEPROP 0 LASTPIN (-5650 4450) $PN 6
R 1
J 0
(-5660 4460);
DISPLAY 0.680851 (-5660 4460);
PAINT MONO (-5660 4460);
FORCEPROP 0 LASTPIN (-5900 4200) $PN 2
J 2
(-5910 4210);
DISPLAY 0.680851 (-5910 4210);
PAINT MONO (-5910 4210);
FORCEPROP 0 LASTPIN (-5650 4050) $PN 1
R 1
J 2
(-5660 4040);
DISPLAY 0.680851 (-5660 4040);
PAINT MONO (-5660 4040);
FORCEPROP 2 LAST PART_TYPE SMLF
J 0
(-5525 4325);
DISPLAY 0.680851 (-5525 4325);
PAINT SKYBLUE (-5525 4325);
FORCEPROP 1 LAST MATERIAL IC
J 0
(-5549 4099);
DISPLAY 0.723404 (-5549 4099);
PAINT SKYBLUE (-5549 4099);
FORCEPROP 2 LAST VALUE PJT138K
J 0
(-5525 4275);
DISPLAY 0.680851 (-5525 4275);
PAINT SKYBLUE (-5525 4275);
FORCEPROP 1 LAST NEEDS_NO_SIZE TRUE
J 0
(-5700 4249);
DISPLAY 0.468085 (-5700 4249);
PAINT GREEN (-5700 4249);
DISPLAY INVISIBLE (-5700 4249);
FORCEPROP 1 LAST CDS_LMAN_SYM_OUTLINE -150,150,150,-150
J 0
(-5700 4250);
DISPLAY 0.468085 (-5700 4250);
PAINT GREEN (-5700 4250);
DISPLAY INVISIBLE (-5700 4250);
FORCEPROP 2 LAST CDS_LIB pure_quanta
J 0
(-5700 4250);
DISPLAY INVISIBLE (-5700 4250);
FORCEPROP 1 LAST PATH I3
J 0
(-5700 4250);
DISPLAY 0.723404 (-5700 4250);
PAINT GREEN (-5700 4250);
DISPLAY INVISIBLE (-5700 4250);
FORCEPROP 1 LAST PART_NUMBER BAM138K0003
J 0
(-5549 4164);
DISPLAY 0.723404 (-5549 4164);
PAINT SKYBLUE (-5549 4164);
DISPLAY INVISIBLE (-5549 4164);
FORCEADD MOSFET_NCH_DUAL..2
(-4900 8175);
FORCEPROP 1 LAST LOCATION Q8000
J 0
(-4749 8151);
DISPLAY 0.723404 (-4749 8151);
PAINT SKYBLUE (-4749 8151);
FORCEPROP 2 LAST SEC 2
J 0
(-4725 8300);
DISPLAY 0.680851 (-4725 8300);
PAINT MONO (-4725 8300);
DISPLAY INVISIBLE (-4725 8300);
FORCEPROP 2 LASTPIN (-4850 8375) $PN 3
R 1
J 0
(-4860 8385);
DISPLAY 0.680851 (-4860 8385);
PAINT MONO (-4860 8385);
FORCEPROP 2 LASTPIN (-5100 8125) $PN 5
J 2
(-5110 8135);
DISPLAY 0.680851 (-5110 8135);
PAINT MONO (-5110 8135);
FORCEPROP 2 LASTPIN (-4850 7975) $PN 4
R 1
J 2
(-4860 7965);
DISPLAY 0.680851 (-4860 7965);
PAINT MONO (-4860 7965);
FORCEPROP 1 LAST MATERIAL IC
J 0
(-4749 8026);
DISPLAY 0.723404 (-4749 8026);
PAINT SKYBLUE (-4749 8026);
FORCEPROP 2 LAST PART_TYPE SMLF
J 0
(-4725 8250);
DISPLAY 0.680851 (-4725 8250);
PAINT SKYBLUE (-4725 8250);
FORCEPROP 2 LAST VALUE PJT138K
J 0
(-4725 8200);
DISPLAY 0.680851 (-4725 8200);
PAINT SKYBLUE (-4725 8200);
FORCEPROP 1 LAST CDS_LMAN_SYM_OUTLINE -150,150,150,-150
J 0
(-4900 8175);
DISPLAY 0.468085 (-4900 8175);
PAINT GREEN (-4900 8175);
DISPLAY INVISIBLE (-4900 8175);
FORCEPROP 1 LAST NEEDS_NO_SIZE TRUE
J 0
(-4750 8066);
DISPLAY 0.468085 (-4750 8066);
PAINT GREEN (-4750 8066);
DISPLAY INVISIBLE (-4750 8066);
FORCEPROP 2 LAST CDS_LIB pure_quanta
J 0
(-4900 8175);
DISPLAY INVISIBLE (-4900 8175);
FORCEPROP 2 LAST SEC_TYPE 
J 0
(-4725 8300);
DISPLAY 0.680851 (-4725 8300);
DISPLAY INVISIBLE (-4725 8300);
FORCEPROP 1 LAST PATH I30
J 0
(-4750 8025);
DISPLAY 0.723404 (-4750 8025);
PAINT GREEN (-4750 8025);
DISPLAY INVISIBLE (-4750 8025);
FORCEPROP 1 LAST PART_NUMBER BAM138K0003
J 0
(-4749 8081);
DISPLAY 0.723404 (-4749 8081);
PAINT SKYBLUE (-4749 8081);
DISPLAY INVISIBLE (-4749 8081);
FORCEADD MOSFET_NCH_DUAL..2
(-4750 6400);
FORCEPROP 1 LAST LOCATION Q9000
J 0
(-4599 6376);
DISPLAY 0.723404 (-4599 6376);
PAINT SKYBLUE (-4599 6376);
FORCEPROP 2 LAST SEC 2
J 0
(-4575 6525);
DISPLAY 0.680851 (-4575 6525);
PAINT MONO (-4575 6525);
DISPLAY INVISIBLE (-4575 6525);
FORCEPROP 2 LASTPIN (-4700 6600) $PN 3
R 1
J 0
(-4710 6610);
DISPLAY 0.680851 (-4710 6610);
PAINT MONO (-4710 6610);
FORCEPROP 2 LASTPIN (-4950 6350) $PN 5
J 2
(-4960 6360);
DISPLAY 0.680851 (-4960 6360);
PAINT MONO (-4960 6360);
FORCEPROP 2 LASTPIN (-4700 6200) $PN 4
R 1
J 2
(-4710 6190);
DISPLAY 0.680851 (-4710 6190);
PAINT MONO (-4710 6190);
FORCEPROP 2 LAST PART_TYPE SMLF
J 0
(-4575 6475);
DISPLAY 0.680851 (-4575 6475);
PAINT SKYBLUE (-4575 6475);
FORCEPROP 2 LAST VALUE PJT138K
J 0
(-4575 6425);
DISPLAY 0.680851 (-4575 6425);
PAINT SKYBLUE (-4575 6425);
FORCEPROP 1 LAST MATERIAL IC
J 0
(-4599 6251);
DISPLAY 0.723404 (-4599 6251);
PAINT SKYBLUE (-4599 6251);
FORCEPROP 1 LAST NEEDS_NO_SIZE TRUE
J 0
(-4600 6291);
DISPLAY 0.468085 (-4600 6291);
PAINT GREEN (-4600 6291);
DISPLAY INVISIBLE (-4600 6291);
FORCEPROP 2 LAST SEC_TYPE 
J 0
(-4575 6525);
DISPLAY 0.680851 (-4575 6525);
DISPLAY INVISIBLE (-4575 6525);
FORCEPROP 1 LAST CDS_LMAN_SYM_OUTLINE -150,150,150,-150
J 0
(-4750 6400);
DISPLAY 0.468085 (-4750 6400);
PAINT GREEN (-4750 6400);
DISPLAY INVISIBLE (-4750 6400);
FORCEPROP 2 LAST CDS_LIB pure_quanta
J 0
(-4750 6400);
DISPLAY INVISIBLE (-4750 6400);
FORCEPROP 1 LAST PATH I31
J 0
(-4600 6250);
DISPLAY 0.723404 (-4600 6250);
PAINT GREEN (-4600 6250);
DISPLAY INVISIBLE (-4600 6250);
FORCEPROP 1 LAST PART_NUMBER BAM138K0003
J 0
(-4599 6306);
DISPLAY 0.723404 (-4599 6306);
PAINT SKYBLUE (-4599 6306);
DISPLAY INVISIBLE (-4599 6306);
FORCEADD Q_RES..2
R 2
(-4700 6950);
FORCEPROP 1 LAST LOCATION R9005
J 2
(-4745 7075);
DISPLAY 0.978723 (-4745 7075);
PAINT SKYBLUE (-4745 7075);
FORCEPROP 0 LAST $SEC 1
J 0
(-4725 7125);
DISPLAY 0.680851 (-4725 7125);
PAINT MONO (-4725 7125);
DISPLAY INVISIBLE (-4725 7125);
FORCEPROP 0 LAST CDS_SEC 1
J 0
(-4725 7125);
DISPLAY 0.680851 (-4725 7125);
DISPLAY INVISIBLE (-4725 7125);
FORCEPROP 1 LASTPIN (-4700 7050) $PN 1
J 2
(-4705 7012);
DISPLAY 0.787234 (-4705 7012);
PAINT MONO (-4705 7012);
FORCEPROP 1 LASTPIN (-4700 6850) $PN 2
J 2
(-4705 6860);
DISPLAY 0.787234 (-4705 6860);
PAINT MONO (-4705 6860);
FORCEPROP 1 LAST VALUE 4.7K
J 2
(-4745 7025);
DISPLAY 0.638298 (-4745 7025);
PAINT SKYBLUE (-4745 7025);
FORCEPROP 1 LAST PACK_TYPE 0402LF
J 2
(-4740 6775);
DISPLAY 0.638298 (-4740 6775);
PAINT SKYBLUE (-4740 6775);
FORCEPROP 1 LAST MATERIAL CHIP
J 2
(-4740 6875);
DISPLAY 0.638298 (-4740 6875);
PAINT SKYBLUE (-4740 6875);
FORCEPROP 1 LAST WATTAGE 1/16W
J 2
(-4740 6925);
DISPLAY 0.638298 (-4740 6925);
PAINT SKYBLUE (-4740 6925);
FORCEPROP 1 LAST TOLERANCE 5%
J 2
(-4745 6975);
DISPLAY 0.638298 (-4745 6975);
PAINT SKYBLUE (-4745 6975);
FORCEPROP 2 LAST CDS_LIB pure_quanta
J 0
(-4700 6950);
DISPLAY INVISIBLE (-4700 6950);
FORCEPROP 1 LAST PATH I32
J 2
(-4750 7125);
DISPLAY 0.978723 (-4750 7125);
PAINT WHITE (-4750 7125);
DISPLAY INVISIBLE (-4750 7125);
FORCEPROP 1 LAST PART_NUMBER CS24702JB10
J 2
(-4740 6825);
DISPLAY 0.638298 (-4740 6825);
PAINT SKYBLUE (-4740 6825);
DISPLAY INVISIBLE (-4740 6825);
FORCEADD UNIVERSAL_GND..1
(-4850 7650);
FORCEPROP 3 LASTPIN (-4850 7700) SIG_NAME GND\g
J 0
(-4840 7710);
DISPLAY 0.659574 (-4840 7710);
PAINT MONO (-4840 7710);
DISPLAY INVISIBLE (-4840 7710);
FORCEPROP 2 LAST CDS_LIB pure_quanta_power
J 0
(-4850 7650);
DISPLAY INVISIBLE (-4850 7650);
FORCEPROP 1 LAST HDL_POWER GND
J 1
(-4825 7575);
DISPLAY 0.872340 (-4825 7575);
PAINT GREEN (-4825 7575);
DISPLAY INVISIBLE (-4825 7575);
FORCEPROP 1 LAST PATH I33
J 0
(-4775 7650);
DISPLAY 0.872340 (-4775 7650);
PAINT AQUA (-4775 7650);
DISPLAY INVISIBLE (-4775 7650);
FORCEADD UNIVERSAL_POWER..1
(-4700 7225);
FORCEPROP 3 LASTPIN (-4700 7175) SIG_NAME P3V3_AUX\g
J 0
(-4690 7185);
DISPLAY 0.659574 (-4690 7185);
PAINT MONO (-4690 7185);
DISPLAY INVISIBLE (-4690 7185);
FORCEPROP 1 LAST HDL_POWER P3V3_AUX
J 1
(-4700 7275);
DISPLAY 0.872340 (-4700 7275);
PAINT GREEN (-4700 7275);
FORCEPROP 2 LAST CDS_LIB pure_quanta_power
J 0
(-4700 7225);
DISPLAY INVISIBLE (-4700 7225);
FORCEPROP 1 LAST PATH I34
J 0
(-4650 7250);
DISPLAY 0.872340 (-4650 7250);
PAINT AQUA (-4650 7250);
DISPLAY INVISIBLE (-4650 7250);
FORCEADD UNIVERSAL_GND..1
(-4150 7750);
FORCEPROP 3 LASTPIN (-4150 7800) SIG_NAME GND\g
J 0
(-4140 7810);
DISPLAY 0.659574 (-4140 7810);
PAINT MONO (-4140 7810);
DISPLAY INVISIBLE (-4140 7810);
FORCEPROP 2 LAST CDS_LIB pure_quanta_power
J 0
(-4150 7750);
DISPLAY INVISIBLE (-4150 7750);
FORCEPROP 1 LAST HDL_POWER GND
J 1
(-4125 7675);
DISPLAY 0.872340 (-4125 7675);
PAINT GREEN (-4125 7675);
DISPLAY INVISIBLE (-4125 7675);
FORCEPROP 1 LAST PATH I35
J 0
(-4075 7750);
DISPLAY 0.872340 (-4075 7750);
PAINT AQUA (-4075 7750);
DISPLAY INVISIBLE (-4075 7750);
FORCEADD Q_CAP..1
(-4150 8125);
FORCEPROP 1 LAST LOCATION C8000
J 0
(-4100 8225);
DISPLAY 0.978723 (-4100 8225);
PAINT SKYBLUE (-4100 8225);
FORCEPROP 0 LAST $SEC 1
J 0
(-4100 8275);
DISPLAY 0.680851 (-4100 8275);
PAINT MONO (-4100 8275);
DISPLAY INVISIBLE (-4100 8275);
FORCEPROP 0 LAST CDS_SEC 1
J 0
(-4100 8275);
DISPLAY 0.680851 (-4100 8275);
DISPLAY INVISIBLE (-4100 8275);
FORCEPROP 1 LASTPIN (-4150 8225) $PN 1
J 0
(-4140 8205);
DISPLAY 0.787234 (-4140 8205);
PAINT MONO (-4140 8205);
FORCEPROP 1 LASTPIN (-4150 8025) $PN 2
J 0
(-4140 8005);
DISPLAY 0.787234 (-4140 8005);
PAINT MONO (-4140 8005);
FORCEPROP 1 LAST PACK_TYPE 0402
J 0
(-4100 7925);
DISPLAY 0.978723 (-4100 7925);
PAINT SKYBLUE (-4100 7925);
FORCEPROP 1 LAST VALUE 1000PF
J 0
(-4100 8175);
DISPLAY 0.978723 (-4100 8175);
PAINT SKYBLUE (-4100 8175);
FORCEPROP 1 LAST MATERIAL EMPTY
J 0
(-4100 8025);
DISPLAY 0.978723 (-4100 8025);
PAINT SKYBLUE (-4100 8025);
FORCEPROP 1 LAST TOLERANCE 5%
J 0
(-4100 8075);
DISPLAY 0.978723 (-4100 8075);
PAINT SKYBLUE (-4100 8075);
FORCEPROP 1 LAST VOLTAGE 50V
J 0
(-4100 8125);
DISPLAY 0.978723 (-4100 8125);
PAINT SKYBLUE (-4100 8125);
FORCEPROP 2 LAST CDS_LIB pure_quanta
J 0
(-4150 8125);
DISPLAY INVISIBLE (-4150 8125);
FORCEPROP 1 LAST PATH I36
J 0
(-4100 8275);
DISPLAY 0.978723 (-4100 8275);
PAINT WHITE (-4100 8275);
DISPLAY INVISIBLE (-4100 8275);
FORCEPROP 1 LAST PART_NUMBER TMP_QCH21006JB10
J 0
(-4100 7975);
DISPLAY 0.978723 (-4100 7975);
PAINT SKYBLUE (-4100 7975);
DISPLAY INVISIBLE (-4100 7975);
FORCEADD OFFPAGE..2
R 2
(-550 3350);
FORCEPROP 2 LAST $XR1 246 
J 0
(-955 3350);
DISPLAY 0.638298 (-955 3350);
PAINT MONO (-955 3350);
FORCEPROP 2 LAST $XR0 121 
J 0
(-835 3350);
DISPLAY 0.638298 (-835 3350);
PAINT MONO (-835 3350);
FORCEPROP 2 LAST CDS_LIB standard
J 0
(-550 3350);
DISPLAY INVISIBLE (-550 3350);
FORCEPROP 1 LAST OFFPAGE TRUE
J 2
(-875 3225);
DISPLAY 0.872340 (-875 3225);
PAINT AQUA (-875 3225);
DISPLAY INVISIBLE (-875 3225);
FORCEPROP 1 LAST COMMENT_BODY TRUE
J 2
(-505 3255);
DISPLAY 0.872340 (-505 3255);
PAINT GREEN (-505 3255);
DISPLAY INVISIBLE (-505 3255);
FORCEPROP 2 LAST PATH I37
J 0
(-800 3400);
DISPLAY 0.680851 (-800 3400);
DISPLAY INVISIBLE (-800 3400);
FORCEADD OFFPAGE..2
R 2
(-550 3550);
FORCEPROP 2 LAST $XR1 246 
J 0
(-955 3550);
DISPLAY 0.638298 (-955 3550);
PAINT MONO (-955 3550);
FORCEPROP 2 LAST $XR0 121 
J 0
(-835 3550);
DISPLAY 0.638298 (-835 3550);
PAINT MONO (-835 3550);
FORCEPROP 2 LAST CDS_LIB standard
J 0
(-550 3550);
DISPLAY INVISIBLE (-550 3550);
FORCEPROP 1 LAST OFFPAGE TRUE
J 2
(-875 3425);
DISPLAY 0.872340 (-875 3425);
PAINT AQUA (-875 3425);
DISPLAY INVISIBLE (-875 3425);
FORCEPROP 1 LAST COMMENT_BODY TRUE
J 2
(-505 3455);
DISPLAY 0.872340 (-505 3455);
PAINT GREEN (-505 3455);
DISPLAY INVISIBLE (-505 3455);
FORCEPROP 2 LAST PATH I38
J 0
(-800 3600);
DISPLAY 0.680851 (-800 3600);
DISPLAY INVISIBLE (-800 3600);
FORCEADD OFFPAGE..2
R 2
(-550 3750);
FORCEPROP 2 LAST $XR1 246 
J 0
(-955 3750);
DISPLAY 0.638298 (-955 3750);
PAINT MONO (-955 3750);
FORCEPROP 2 LAST $XR0 121 
J 0
(-835 3750);
DISPLAY 0.638298 (-835 3750);
PAINT MONO (-835 3750);
FORCEPROP 2 LAST CDS_LIB standard
J 0
(-550 3750);
DISPLAY INVISIBLE (-550 3750);
FORCEPROP 1 LAST OFFPAGE TRUE
J 2
(-875 3625);
DISPLAY 0.872340 (-875 3625);
PAINT AQUA (-875 3625);
DISPLAY INVISIBLE (-875 3625);
FORCEPROP 1 LAST COMMENT_BODY TRUE
J 2
(-505 3655);
DISPLAY 0.872340 (-505 3655);
PAINT GREEN (-505 3655);
DISPLAY INVISIBLE (-505 3655);
FORCEPROP 2 LAST PATH I39
J 0
(-800 3800);
DISPLAY 0.680851 (-800 3800);
DISPLAY INVISIBLE (-800 3800);
FORCEADD UNIVERSAL_GND..1
(-5650 3700);
FORCEPROP 3 LASTPIN (-5650 3750) SIG_NAME GND\g
J 0
(-5640 3760);
DISPLAY 0.659574 (-5640 3760);
PAINT MONO (-5640 3760);
DISPLAY INVISIBLE (-5640 3760);
FORCEPROP 2 LAST CDS_LIB pure_quanta_power
J 0
(-5650 3700);
DISPLAY INVISIBLE (-5650 3700);
FORCEPROP 1 LAST HDL_POWER GND
J 1
(-5625 3625);
DISPLAY 0.872340 (-5625 3625);
PAINT GREEN (-5625 3625);
DISPLAY INVISIBLE (-5625 3625);
FORCEPROP 1 LAST PATH I4
J 0
(-5575 3700);
DISPLAY 0.872340 (-5575 3700);
PAINT AQUA (-5575 3700);
DISPLAY INVISIBLE (-5575 3700);
FORCEADD OFFPAGE..2
R 2
(-550 3950);
FORCEPROP 2 LAST $XR1 246 
J 0
(-955 3950);
DISPLAY 0.638298 (-955 3950);
PAINT MONO (-955 3950);
FORCEPROP 2 LAST $XR0 121 
J 0
(-835 3950);
DISPLAY 0.638298 (-835 3950);
PAINT MONO (-835 3950);
FORCEPROP 2 LAST CDS_LIB standard
J 0
(-550 3950);
DISPLAY INVISIBLE (-550 3950);
FORCEPROP 1 LAST OFFPAGE TRUE
J 2
(-875 3825);
DISPLAY 0.872340 (-875 3825);
PAINT AQUA (-875 3825);
DISPLAY INVISIBLE (-875 3825);
FORCEPROP 1 LAST COMMENT_BODY TRUE
J 2
(-505 3855);
DISPLAY 0.872340 (-505 3855);
PAINT GREEN (-505 3855);
DISPLAY INVISIBLE (-505 3855);
FORCEPROP 2 LAST PATH I40
J 0
(-800 4000);
DISPLAY 0.680851 (-800 4000);
DISPLAY INVISIBLE (-800 4000);
FORCEADD UNIVERSAL_GND..1
(-3950 4175);
FORCEPROP 3 LASTPIN (-3950 4225) SIG_NAME GND\g
J 0
(-3940 4235);
DISPLAY 0.659574 (-3940 4235);
PAINT MONO (-3940 4235);
DISPLAY INVISIBLE (-3940 4235);
FORCEPROP 2 LAST CDS_LIB pure_quanta_power
J 0
(-3950 4175);
DISPLAY INVISIBLE (-3950 4175);
FORCEPROP 1 LAST HDL_POWER GND
J 1
(-3925 4100);
DISPLAY 0.872340 (-3925 4100);
PAINT GREEN (-3925 4100);
DISPLAY INVISIBLE (-3925 4100);
FORCEPROP 1 LAST PATH I41
J 0
(-3875 4175);
DISPLAY 0.872340 (-3875 4175);
PAINT AQUA (-3875 4175);
DISPLAY INVISIBLE (-3875 4175);
FORCEADD Q_CAP..1
(-3950 4550);
FORCEPROP 1 LAST LOCATION C9001
J 0
(-3900 4650);
DISPLAY 0.978723 (-3900 4650);
PAINT SKYBLUE (-3900 4650);
FORCEPROP 0 LAST $SEC 1
J 0
(-3900 4700);
DISPLAY 0.680851 (-3900 4700);
PAINT MONO (-3900 4700);
DISPLAY INVISIBLE (-3900 4700);
FORCEPROP 0 LAST CDS_SEC 1
J 0
(-3900 4700);
DISPLAY 0.680851 (-3900 4700);
DISPLAY INVISIBLE (-3900 4700);
FORCEPROP 1 LASTPIN (-3950 4650) $PN 1
J 0
(-3940 4630);
DISPLAY 0.787234 (-3940 4630);
PAINT MONO (-3940 4630);
FORCEPROP 1 LASTPIN (-3950 4450) $PN 2
J 0
(-3940 4430);
DISPLAY 0.787234 (-3940 4430);
PAINT MONO (-3940 4430);
FORCEPROP 1 LAST VALUE 1000PF
J 0
(-3900 4600);
DISPLAY 0.978723 (-3900 4600);
PAINT SKYBLUE (-3900 4600);
FORCEPROP 1 LAST VOLTAGE 50V
J 0
(-3900 4550);
DISPLAY 0.978723 (-3900 4550);
PAINT SKYBLUE (-3900 4550);
FORCEPROP 1 LAST MATERIAL EMPTY
J 0
(-3900 4450);
DISPLAY 0.978723 (-3900 4450);
PAINT SKYBLUE (-3900 4450);
FORCEPROP 1 LAST PACK_TYPE 0402
J 0
(-3900 4350);
DISPLAY 0.978723 (-3900 4350);
PAINT SKYBLUE (-3900 4350);
FORCEPROP 1 LAST TOLERANCE 5%
J 0
(-3900 4500);
DISPLAY 0.978723 (-3900 4500);
PAINT SKYBLUE (-3900 4500);
FORCEPROP 2 LAST CDS_LIB pure_quanta
J 0
(-3950 4550);
DISPLAY INVISIBLE (-3950 4550);
FORCEPROP 1 LAST PATH I42
J 0
(-3900 4700);
DISPLAY 0.978723 (-3900 4700);
PAINT WHITE (-3900 4700);
DISPLAY INVISIBLE (-3900 4700);
FORCEPROP 1 LAST PART_NUMBER TMP_QCH21006JB10
J 0
(-3900 4400);
DISPLAY 0.978723 (-3900 4400);
PAINT SKYBLUE (-3900 4400);
DISPLAY INVISIBLE (-3900 4400);
FORCEADD OFFPAGE..2
(-3600 4900);
FORCEPROP 2 LAST $XR0 246 
J 0
(-3411 4900);
DISPLAY 0.638298 (-3411 4900);
PAINT MONO (-3411 4900);
FORCEPROP 2 LAST CDS_LIB standard
J 0
(-3600 4900);
DISPLAY INVISIBLE (-3600 4900);
FORCEPROP 1 LAST OFFPAGE TRUE
J 0
(-3275 4775);
DISPLAY 0.872340 (-3275 4775);
PAINT AQUA (-3275 4775);
DISPLAY INVISIBLE (-3275 4775);
FORCEPROP 1 LAST COMMENT_BODY TRUE
J 0
(-3645 4805);
DISPLAY 0.872340 (-3645 4805);
PAINT GREEN (-3645 4805);
DISPLAY INVISIBLE (-3645 4805);
FORCEPROP 2 LAST PATH I43
J 0
(-3400 4950);
DISPLAY 0.680851 (-3400 4950);
DISPLAY INVISIBLE (-3400 4950);
FORCEADD UNIVERSAL_GND..1
(-4000 5975);
FORCEPROP 3 LASTPIN (-4000 6025) SIG_NAME GND\g
J 0
(-3990 6035);
DISPLAY 0.659574 (-3990 6035);
PAINT MONO (-3990 6035);
DISPLAY INVISIBLE (-3990 6035);
FORCEPROP 2 LAST CDS_LIB pure_quanta_power
J 0
(-4000 5975);
DISPLAY INVISIBLE (-4000 5975);
FORCEPROP 1 LAST HDL_POWER GND
J 1
(-3975 5900);
DISPLAY 0.872340 (-3975 5900);
PAINT GREEN (-3975 5900);
DISPLAY INVISIBLE (-3975 5900);
FORCEPROP 1 LAST PATH I44
J 0
(-3925 5975);
DISPLAY 0.872340 (-3925 5975);
PAINT AQUA (-3925 5975);
DISPLAY INVISIBLE (-3925 5975);
FORCEADD Q_CAP..1
(-4000 6350);
FORCEPROP 1 LAST LOCATION C9000
J 0
(-3950 6450);
DISPLAY 0.978723 (-3950 6450);
PAINT SKYBLUE (-3950 6450);
FORCEPROP 0 LAST $SEC 1
J 0
(-3950 6500);
DISPLAY 0.680851 (-3950 6500);
PAINT MONO (-3950 6500);
DISPLAY INVISIBLE (-3950 6500);
FORCEPROP 0 LAST CDS_SEC 1
J 0
(-3950 6500);
DISPLAY 0.680851 (-3950 6500);
DISPLAY INVISIBLE (-3950 6500);
FORCEPROP 1 LASTPIN (-4000 6450) $PN 1
J 0
(-3990 6430);
DISPLAY 0.787234 (-3990 6430);
PAINT MONO (-3990 6430);
FORCEPROP 1 LASTPIN (-4000 6250) $PN 2
J 0
(-3990 6230);
DISPLAY 0.787234 (-3990 6230);
PAINT MONO (-3990 6230);
FORCEPROP 1 LAST VALUE 1000PF
J 0
(-3950 6400);
DISPLAY 0.978723 (-3950 6400);
PAINT SKYBLUE (-3950 6400);
FORCEPROP 1 LAST VOLTAGE 50V
J 0
(-3950 6350);
DISPLAY 0.978723 (-3950 6350);
PAINT SKYBLUE (-3950 6350);
FORCEPROP 1 LAST PACK_TYPE 0402
J 0
(-3950 6150);
DISPLAY 0.978723 (-3950 6150);
PAINT SKYBLUE (-3950 6150);
FORCEPROP 1 LAST MATERIAL EMPTY
J 0
(-3950 6250);
DISPLAY 0.978723 (-3950 6250);
PAINT SKYBLUE (-3950 6250);
FORCEPROP 1 LAST TOLERANCE 5%
J 0
(-3950 6300);
DISPLAY 0.978723 (-3950 6300);
PAINT SKYBLUE (-3950 6300);
FORCEPROP 2 LAST CDS_LIB pure_quanta
J 0
(-4000 6350);
DISPLAY INVISIBLE (-4000 6350);
FORCEPROP 1 LAST PATH I45
J 0
(-3950 6500);
DISPLAY 0.978723 (-3950 6500);
PAINT WHITE (-3950 6500);
DISPLAY INVISIBLE (-3950 6500);
FORCEPROP 1 LAST PART_NUMBER TMP_QCH21006JB10
J 0
(-3950 6200);
DISPLAY 0.978723 (-3950 6200);
PAINT SKYBLUE (-3950 6200);
DISPLAY INVISIBLE (-3950 6200);
FORCEADD OFFPAGE..2
(-3650 6700);
FORCEPROP 2 LAST $XR0 246 
J 0
(-3461 6700);
DISPLAY 0.638298 (-3461 6700);
PAINT MONO (-3461 6700);
FORCEPROP 2 LAST CDS_LIB standard
J 2
(-3650 6700);
DISPLAY INVISIBLE (-3650 6700);
FORCEPROP 1 LAST OFFPAGE TRUE
J 0
(-3325 6575);
DISPLAY 0.872340 (-3325 6575);
PAINT AQUA (-3325 6575);
DISPLAY INVISIBLE (-3325 6575);
FORCEPROP 1 LAST COMMENT_BODY TRUE
J 0
(-3695 6605);
DISPLAY 0.872340 (-3695 6605);
PAINT GREEN (-3695 6605);
DISPLAY INVISIBLE (-3695 6605);
FORCEPROP 2 LAST PATH I46
J 0
(-3450 6750);
DISPLAY 0.680851 (-3450 6750);
DISPLAY INVISIBLE (-3450 6750);
FORCEADD OFFPAGE..4
R 2
(-2100 7775);
FORCEPROP 2 LAST $XR0 118 
J 0
(-2352 7775);
DISPLAY 0.638298 (-2352 7775);
PAINT MONO (-2352 7775);
FORCEPROP 2 LAST CDS_LIB standard
J 0
(-2100 7775);
DISPLAY INVISIBLE (-2100 7775);
FORCEPROP 1 LAST OFFPAGE TRUE
J 2
(-2425 7650);
DISPLAY 0.872340 (-2425 7650);
PAINT GREEN (-2425 7650);
DISPLAY INVISIBLE (-2425 7650);
FORCEPROP 1 LAST COMMENT_BODY TRUE
J 2
(-2075 7675);
DISPLAY 0.872340 (-2075 7675);
PAINT GREEN (-2075 7675);
DISPLAY INVISIBLE (-2075 7675);
FORCEPROP 2 LAST PATH I47
J 0
(-2350 7825);
DISPLAY 0.680851 (-2350 7825);
DISPLAY INVISIBLE (-2350 7825);
FORCEADD OFFPAGE..2
R 2
(-550 4175);
FORCEPROP 2 LAST $XR1 122 
J 0
(-955 4175);
DISPLAY 0.638298 (-955 4175);
PAINT MONO (-955 4175);
FORCEPROP 2 LAST $XR0 124 
J 0
(-835 4175);
DISPLAY 0.638298 (-835 4175);
PAINT MONO (-835 4175);
FORCEPROP 2 LAST CDS_LIB standard
J 0
(-550 4175);
DISPLAY INVISIBLE (-550 4175);
FORCEPROP 1 LAST OFFPAGE TRUE
J 2
(-875 4050);
DISPLAY 0.872340 (-875 4050);
PAINT AQUA (-875 4050);
DISPLAY INVISIBLE (-875 4050);
FORCEPROP 1 LAST COMMENT_BODY TRUE
J 2
(-505 4080);
DISPLAY 0.872340 (-505 4080);
PAINT GREEN (-505 4080);
DISPLAY INVISIBLE (-505 4080);
FORCEPROP 2 LAST PATH I48
J 0
(-800 4225);
DISPLAY 0.680851 (-800 4225);
DISPLAY INVISIBLE (-800 4225);
FORCEADD UNIVERSAL_GND..1
(-1300 7200);
FORCEPROP 3 LASTPIN (-1300 7250) SIG_NAME GND\g
J 0
(-1290 7260);
DISPLAY 0.659574 (-1290 7260);
PAINT MONO (-1290 7260);
DISPLAY INVISIBLE (-1290 7260);
FORCEPROP 2 LAST CDS_LIB pure_quanta_power
J 0
(-1300 7200);
DISPLAY INVISIBLE (-1300 7200);
FORCEPROP 1 LAST HDL_POWER GND
J 1
(-1275 7125);
DISPLAY 0.872340 (-1275 7125);
PAINT GREEN (-1275 7125);
DISPLAY INVISIBLE (-1275 7125);
FORCEPROP 1 LAST PATH I49
J 0
(-1225 7200);
DISPLAY 0.872340 (-1225 7200);
PAINT AQUA (-1225 7200);
DISPLAY INVISIBLE (-1225 7200);
FORCEADD UNIVERSAL_GND..1
(-4650 4075);
FORCEPROP 3 LASTPIN (-4650 4125) SIG_NAME GND\g
J 0
(-4640 4135);
DISPLAY 0.659574 (-4640 4135);
PAINT MONO (-4640 4135);
DISPLAY INVISIBLE (-4640 4135);
FORCEPROP 2 LAST CDS_LIB pure_quanta_power
J 0
(-4650 4075);
DISPLAY INVISIBLE (-4650 4075);
FORCEPROP 1 LAST HDL_POWER GND
J 1
(-4625 4000);
DISPLAY 0.872340 (-4625 4000);
PAINT GREEN (-4625 4000);
DISPLAY INVISIBLE (-4625 4000);
FORCEPROP 1 LAST PATH I5
J 0
(-4575 4075);
DISPLAY 0.872340 (-4575 4075);
PAINT AQUA (-4575 4075);
DISPLAY INVISIBLE (-4575 4075);
FORCEADD Q_RES..2
R 2
(-1300 7525);
FORCEPROP 1 LAST LOCATION R9015
J 2
(-1345 7650);
DISPLAY 0.978723 (-1345 7650);
PAINT SKYBLUE (-1345 7650);
FORCEPROP 0 LAST $SEC 1
J 0
(-1325 7700);
DISPLAY 0.680851 (-1325 7700);
PAINT MONO (-1325 7700);
DISPLAY INVISIBLE (-1325 7700);
FORCEPROP 0 LAST CDS_SEC 1
J 0
(-1325 7700);
DISPLAY 0.680851 (-1325 7700);
DISPLAY INVISIBLE (-1325 7700);
FORCEPROP 1 LASTPIN (-1300 7625) $PN 1
J 2
(-1305 7587);
DISPLAY 0.787234 (-1305 7587);
PAINT MONO (-1305 7587);
FORCEPROP 1 LASTPIN (-1300 7425) $PN 2
J 2
(-1305 7435);
DISPLAY 0.787234 (-1305 7435);
PAINT MONO (-1305 7435);
FORCEPROP 1 LAST PACK_TYPE 0402LF
J 2
(-1340 7350);
DISPLAY 0.978723 (-1340 7350);
PAINT SKYBLUE (-1340 7350);
FORCEPROP 1 LAST WATTAGE 1/16W
J 2
(-1340 7500);
DISPLAY 0.978723 (-1340 7500);
PAINT SKYBLUE (-1340 7500);
FORCEPROP 1 LAST MATERIAL EMPTY
J 2
(-1340 7450);
DISPLAY 0.978723 (-1340 7450);
PAINT SKYBLUE (-1340 7450);
FORCEPROP 1 LAST TOLERANCE 1%
J 2
(-1345 7550);
DISPLAY 0.978723 (-1345 7550);
PAINT SKYBLUE (-1345 7550);
FORCEPROP 1 LAST VALUE 100K
J 2
(-1345 7600);
DISPLAY 0.978723 (-1345 7600);
PAINT SKYBLUE (-1345 7600);
FORCEPROP 2 LAST CDS_LIB pure_quanta
J 0
(-1300 7525);
DISPLAY INVISIBLE (-1300 7525);
FORCEPROP 1 LAST PATH I50
J 2
(-1350 7700);
DISPLAY 0.978723 (-1350 7700);
PAINT WHITE (-1350 7700);
DISPLAY INVISIBLE (-1350 7700);
FORCEPROP 1 LAST PART_NUMBER CS41002FB09
J 2
(-1340 7400);
DISPLAY 0.978723 (-1340 7400);
PAINT SKYBLUE (-1340 7400);
DISPLAY INVISIBLE (-1340 7400);
FORCEADD Q_RES..2
R 2
(-1325 8150);
FORCEPROP 1 LAST LOCATION R9014
J 2
(-1370 8275);
DISPLAY 0.808511 (-1370 8275);
FORCEPROP 0 LAST $SEC 1
J 0
(-1350 8325);
DISPLAY 0.680851 (-1350 8325);
PAINT MONO (-1350 8325);
DISPLAY INVISIBLE (-1350 8325);
FORCEPROP 0 LAST CDS_SEC 1
J 0
(-1350 8325);
DISPLAY 0.680851 (-1350 8325);
DISPLAY INVISIBLE (-1350 8325);
FORCEPROP 1 LASTPIN (-1325 8250) $PN 1
J 2
(-1330 8212);
DISPLAY 0.787234 (-1330 8212);
PAINT MONO (-1330 8212);
FORCEPROP 1 LASTPIN (-1325 8050) $PN 2
J 2
(-1330 8060);
DISPLAY 0.787234 (-1330 8060);
PAINT MONO (-1330 8060);
FORCEPROP 1 LAST VALUE 10K
J 2
(-1370 8225);
DISPLAY 0.638298 (-1370 8225);
FORCEPROP 1 LAST PACK_TYPE 0402LF
J 2
(-1365 7975);
DISPLAY 0.638298 (-1365 7975);
FORCEPROP 1 LAST MATERIAL CHIP
J 2
(-1365 8075);
DISPLAY 0.638298 (-1365 8075);
FORCEPROP 1 LAST WATTAGE 1/16W
J 2
(-1365 8125);
DISPLAY 0.638298 (-1365 8125);
FORCEPROP 1 LAST TOLERANCE 1%
J 2
(-1370 8175);
DISPLAY 0.638298 (-1370 8175);
FORCEPROP 2 LAST CDS_LIB pure_quanta
J 0
(-1325 8150);
DISPLAY INVISIBLE (-1325 8150);
FORCEPROP 1 LAST PATH I51
J 2
(-1375 8325);
DISPLAY 0.978723 (-1375 8325);
PAINT WHITE (-1375 8325);
DISPLAY INVISIBLE (-1375 8325);
FORCEPROP 1 LAST PART_NUMBER CS31002FB08
J 2
(-1365 8025);
DISPLAY 0.638298 (-1365 8025);
DISPLAY INVISIBLE (-1365 8025);
FORCEADD MOSFET_NCH_DUAL..1
(-975 7825);
FORCEPROP 1 LAST LOCATION Q9002
J 0
(-824 7799);
DISPLAY 0.723404 (-824 7799);
PAINT SKYBLUE (-824 7799);
FORCEPROP 0 LAST $SEC 1
J 0
(-800 7950);
DISPLAY 0.680851 (-800 7950);
PAINT MONO (-800 7950);
DISPLAY INVISIBLE (-800 7950);
FORCEPROP 0 LAST CDS_SEC 1
J 0
(-800 7950);
DISPLAY 0.680851 (-800 7950);
DISPLAY INVISIBLE (-800 7950);
FORCEPROP 0 LASTPIN (-925 8025) $PN 6
R 1
J 0
(-935 8035);
DISPLAY 0.680851 (-935 8035);
PAINT MONO (-935 8035);
FORCEPROP 0 LASTPIN (-1175 7775) $PN 2
J 2
(-1185 7785);
DISPLAY 0.680851 (-1185 7785);
PAINT MONO (-1185 7785);
FORCEPROP 0 LASTPIN (-925 7625) $PN 1
R 1
J 2
(-935 7615);
DISPLAY 0.680851 (-935 7615);
PAINT MONO (-935 7615);
FORCEPROP 2 LAST VALUE PJT138K
J 0
(-800 7850);
DISPLAY 0.680851 (-800 7850);
PAINT SKYBLUE (-800 7850);
FORCEPROP 2 LAST PART_TYPE SMLF
J 0
(-800 7900);
DISPLAY 0.680851 (-800 7900);
PAINT SKYBLUE (-800 7900);
FORCEPROP 1 LAST MATERIAL IC
J 0
(-824 7674);
DISPLAY 0.723404 (-824 7674);
PAINT SKYBLUE (-824 7674);
FORCEPROP 1 LAST NEEDS_NO_SIZE TRUE
J 0
(-975 7824);
DISPLAY 0.468085 (-975 7824);
PAINT GREEN (-975 7824);
DISPLAY INVISIBLE (-975 7824);
FORCEPROP 1 LAST CDS_LMAN_SYM_OUTLINE -150,150,150,-150
J 0
(-975 7825);
DISPLAY 0.468085 (-975 7825);
PAINT GREEN (-975 7825);
DISPLAY INVISIBLE (-975 7825);
FORCEPROP 2 LAST CDS_LIB pure_quanta
J 0
(-975 7825);
DISPLAY INVISIBLE (-975 7825);
FORCEPROP 1 LAST PATH I52
J 0
(-975 7825);
DISPLAY 0.723404 (-975 7825);
PAINT GREEN (-975 7825);
DISPLAY INVISIBLE (-975 7825);
FORCEPROP 1 LAST PART_NUMBER BAM138K0003
J 0
(-824 7739);
DISPLAY 0.723404 (-824 7739);
PAINT SKYBLUE (-824 7739);
DISPLAY INVISIBLE (-824 7739);
FORCEADD UNIVERSAL_GND..1
(-925 7275);
FORCEPROP 3 LASTPIN (-925 7325) SIG_NAME GND\g
J 0
(-915 7335);
DISPLAY 0.659574 (-915 7335);
PAINT MONO (-915 7335);
DISPLAY INVISIBLE (-915 7335);
FORCEPROP 2 LAST CDS_LIB pure_quanta_power
J 0
(-925 7275);
DISPLAY INVISIBLE (-925 7275);
FORCEPROP 1 LAST HDL_POWER GND
J 1
(-900 7200);
DISPLAY 0.872340 (-900 7200);
PAINT GREEN (-900 7200);
DISPLAY INVISIBLE (-900 7200);
FORCEPROP 1 LAST PATH I53
J 0
(-850 7275);
DISPLAY 0.872340 (-850 7275);
PAINT AQUA (-850 7275);
DISPLAY INVISIBLE (-850 7275);
FORCEADD UNIVERSAL_POWER..1
(-6300 8450);
FORCEPROP 3 LASTPIN (-6300 8400) SIG_NAME P3V3_AUX\g
J 0
(-6290 8410);
DISPLAY 0.659574 (-6290 8410);
PAINT MONO (-6290 8410);
DISPLAY INVISIBLE (-6290 8410);
FORCEPROP 1 LAST HDL_POWER P3V3_AUX
J 1
(-6300 8500);
DISPLAY 0.872340 (-6300 8500);
PAINT GREEN (-6300 8500);
FORCEPROP 2 LAST CDS_LIB pure_quanta_power
J 0
(-6300 8450);
DISPLAY INVISIBLE (-6300 8450);
FORCEPROP 1 LAST PATH I54
J 0
(-6250 8475);
DISPLAY 0.872340 (-6250 8475);
PAINT AQUA (-6250 8475);
DISPLAY INVISIBLE (-6250 8475);
FORCEADD Q_RES..2
R 2
(-5675 8475);
FORCEPROP 1 LAST LOCATION R8002
J 2
(-5720 8600);
DISPLAY 0.638298 (-5720 8600);
PAINT SKYBLUE (-5720 8600);
FORCEPROP 0 LAST $SEC 1
J 0
(-5700 8650);
DISPLAY 0.680851 (-5700 8650);
PAINT MONO (-5700 8650);
DISPLAY INVISIBLE (-5700 8650);
FORCEPROP 0 LAST CDS_SEC 1
J 0
(-5700 8650);
DISPLAY 0.680851 (-5700 8650);
DISPLAY INVISIBLE (-5700 8650);
FORCEPROP 1 LASTPIN (-5675 8575) $PN 1
J 2
(-5680 8537);
DISPLAY 0.787234 (-5680 8537);
PAINT MONO (-5680 8537);
FORCEPROP 1 LASTPIN (-5675 8375) $PN 2
J 2
(-5680 8385);
DISPLAY 0.787234 (-5680 8385);
PAINT MONO (-5680 8385);
FORCEPROP 1 LAST PACK_TYPE 0402LF
J 2
(-5715 8300);
DISPLAY 0.638298 (-5715 8300);
PAINT SKYBLUE (-5715 8300);
FORCEPROP 1 LAST WATTAGE 1/16W
J 2
(-5715 8450);
DISPLAY 0.638298 (-5715 8450);
PAINT SKYBLUE (-5715 8450);
FORCEPROP 1 LAST VALUE 4.7K
J 2
(-5720 8550);
DISPLAY 0.638298 (-5720 8550);
PAINT SKYBLUE (-5720 8550);
FORCEPROP 1 LAST MATERIAL CHIP
J 2
(-5715 8400);
DISPLAY 0.638298 (-5715 8400);
PAINT SKYBLUE (-5715 8400);
FORCEPROP 1 LAST TOLERANCE 5%
J 2
(-5720 8500);
DISPLAY 0.638298 (-5720 8500);
PAINT SKYBLUE (-5720 8500);
FORCEPROP 2 LAST CDS_LIB pure_quanta
J 2
(-5675 8475);
DISPLAY INVISIBLE (-5675 8475);
FORCEPROP 1 LAST PATH I55
J 2
(-5725 8650);
DISPLAY 0.978723 (-5725 8650);
PAINT WHITE (-5725 8650);
DISPLAY INVISIBLE (-5725 8650);
FORCEPROP 1 LAST PART_NUMBER CS24702JB10
J 2
(-5715 8350);
DISPLAY 0.638298 (-5715 8350);
PAINT SKYBLUE (-5715 8350);
DISPLAY INVISIBLE (-5715 8350);
FORCEADD UNIVERSAL_POWER..1
(-5675 8825);
FORCEPROP 3 LASTPIN (-5675 8775) SIG_NAME P3V3_AUX\g
J 0
(-5665 8785);
DISPLAY 0.659574 (-5665 8785);
PAINT MONO (-5665 8785);
DISPLAY INVISIBLE (-5665 8785);
FORCEPROP 1 LAST HDL_POWER P3V3_AUX
J 1
(-5675 8875);
DISPLAY 0.872340 (-5675 8875);
PAINT GREEN (-5675 8875);
FORCEPROP 2 LAST CDS_LIB pure_quanta_power
J 0
(-5675 8825);
DISPLAY INVISIBLE (-5675 8825);
FORCEPROP 1 LAST PATH I56
J 0
(-5625 8850);
DISPLAY 0.872340 (-5625 8850);
PAINT AQUA (-5625 8850);
DISPLAY INVISIBLE (-5625 8850);
FORCEADD Q_RES..2
R 2
(-4850 8725);
FORCEPROP 1 LAST LOCATION R8003
J 2
(-4895 8850);
DISPLAY 0.978723 (-4895 8850);
PAINT SKYBLUE (-4895 8850);
FORCEPROP 0 LAST $SEC 1
J 0
(-4875 8900);
DISPLAY 0.680851 (-4875 8900);
PAINT MONO (-4875 8900);
DISPLAY INVISIBLE (-4875 8900);
FORCEPROP 0 LAST CDS_SEC 1
J 0
(-4875 8900);
DISPLAY 0.680851 (-4875 8900);
DISPLAY INVISIBLE (-4875 8900);
FORCEPROP 1 LASTPIN (-4850 8825) $PN 1
J 2
(-4855 8787);
DISPLAY 0.787234 (-4855 8787);
PAINT MONO (-4855 8787);
FORCEPROP 1 LASTPIN (-4850 8625) $PN 2
J 2
(-4855 8635);
DISPLAY 0.787234 (-4855 8635);
PAINT MONO (-4855 8635);
FORCEPROP 1 LAST PACK_TYPE 0402LF
J 2
(-4890 8550);
DISPLAY 0.638298 (-4890 8550);
PAINT SKYBLUE (-4890 8550);
FORCEPROP 1 LAST WATTAGE 1/16W
J 2
(-4890 8700);
DISPLAY 0.638298 (-4890 8700);
PAINT SKYBLUE (-4890 8700);
FORCEPROP 1 LAST TOLERANCE 5%
J 2
(-4895 8750);
DISPLAY 0.638298 (-4895 8750);
PAINT SKYBLUE (-4895 8750);
FORCEPROP 1 LAST VALUE 4.7K
J 2
(-4895 8800);
DISPLAY 0.638298 (-4895 8800);
PAINT SKYBLUE (-4895 8800);
FORCEPROP 1 LAST MATERIAL CHIP
J 2
(-4890 8650);
DISPLAY 0.638298 (-4890 8650);
PAINT SKYBLUE (-4890 8650);
FORCEPROP 2 LAST CDS_LIB pure_quanta
J 0
(-4850 8725);
DISPLAY INVISIBLE (-4850 8725);
FORCEPROP 1 LAST PATH I57
J 2
(-4900 8900);
DISPLAY 0.978723 (-4900 8900);
PAINT WHITE (-4900 8900);
DISPLAY INVISIBLE (-4900 8900);
FORCEPROP 1 LAST PART_NUMBER CS24702JB10
J 2
(-4890 8600);
DISPLAY 0.638298 (-4890 8600);
PAINT SKYBLUE (-4890 8600);
DISPLAY INVISIBLE (-4890 8600);
FORCEADD UNIVERSAL_POWER..1
(-4850 9000);
FORCEPROP 3 LASTPIN (-4850 8950) SIG_NAME P3V3_AUX\g
J 0
(-4840 8960);
DISPLAY 0.659574 (-4840 8960);
PAINT MONO (-4840 8960);
DISPLAY INVISIBLE (-4840 8960);
FORCEPROP 1 LAST HDL_POWER P3V3_AUX
J 1
(-4850 9050);
DISPLAY 0.872340 (-4850 9050);
PAINT GREEN (-4850 9050);
FORCEPROP 2 LAST CDS_LIB pure_quanta_power
J 0
(-4850 9000);
DISPLAY INVISIBLE (-4850 9000);
FORCEPROP 1 LAST PATH I58
J 0
(-4800 9025);
DISPLAY 0.872340 (-4800 9025);
PAINT AQUA (-4800 9025);
DISPLAY INVISIBLE (-4800 9025);
FORCEADD OFFPAGE..2
(-3800 8475);
FORCEPROP 2 LAST $XR1 246 
J 0
(-3521 8475);
DISPLAY 0.638298 (-3521 8475);
PAINT MONO (-3521 8475);
FORCEPROP 2 LAST $XR0 81 
J 0
(-3611 8475);
DISPLAY 0.638298 (-3611 8475);
PAINT MONO (-3611 8475);
FORCEPROP 2 LAST CDS_LIB standard
J 2
(-3800 8475);
DISPLAY INVISIBLE (-3800 8475);
FORCEPROP 1 LAST OFFPAGE TRUE
J 0
(-3475 8350);
DISPLAY 0.872340 (-3475 8350);
PAINT AQUA (-3475 8350);
DISPLAY INVISIBLE (-3475 8350);
FORCEPROP 1 LAST COMMENT_BODY TRUE
J 0
(-3845 8380);
DISPLAY 0.872340 (-3845 8380);
PAINT GREEN (-3845 8380);
DISPLAY INVISIBLE (-3845 8380);
FORCEPROP 2 LAST PATH I59
J 0
(-3500 8525);
DISPLAY 0.680851 (-3500 8525);
DISPLAY INVISIBLE (-3500 8525);
FORCEADD OFFPAGE..4
R 2
(-6825 4200);
FORCEPROP 2 LAST $XR0 117 
J 0
(-7077 4200);
DISPLAY 0.638298 (-7077 4200);
PAINT MONO (-7077 4200);
FORCEPROP 2 LAST CDS_LIB standard
J 0
(-6825 4200);
DISPLAY INVISIBLE (-6825 4200);
FORCEPROP 1 LAST OFFPAGE TRUE
J 2
(-7150 4075);
DISPLAY 0.872340 (-7150 4075);
PAINT GREEN (-7150 4075);
DISPLAY INVISIBLE (-7150 4075);
FORCEPROP 1 LAST COMMENT_BODY TRUE
J 2
(-6800 4100);
DISPLAY 0.872340 (-6800 4100);
PAINT GREEN (-6800 4100);
DISPLAY INVISIBLE (-6800 4100);
FORCEPROP 2 LAST PATH I6
J 0
(-7075 4250);
DISPLAY 0.680851 (-7075 4250);
DISPLAY INVISIBLE (-7075 4250);
FORCEADD UNIVERSAL_POWER..1
(-1325 8450);
FORCEPROP 3 LASTPIN (-1325 8400) SIG_NAME P3V3_AUX\g
J 0
(-1315 8410);
DISPLAY 0.659574 (-1315 8410);
PAINT MONO (-1315 8410);
DISPLAY INVISIBLE (-1315 8410);
FORCEPROP 1 LAST HDL_POWER P3V3_AUX
J 1
(-1325 8500);
DISPLAY 0.872340 (-1325 8500);
PAINT GREEN (-1325 8500);
FORCEPROP 2 LAST CDS_LIB pure_quanta_power
J 0
(-1325 8450);
DISPLAY INVISIBLE (-1325 8450);
FORCEPROP 1 LAST PATH I60
J 0
(-1275 8475);
DISPLAY 0.872340 (-1275 8475);
PAINT AQUA (-1275 8475);
DISPLAY INVISIBLE (-1275 8475);
FORCEADD Q_RES..2
R 2
(-925 8475);
FORCEPROP 1 LAST LOCATION R9016
J 2
(-970 8600);
DISPLAY 0.638298 (-970 8600);
PAINT SKYBLUE (-970 8600);
FORCEPROP 0 LAST $SEC 1
J 0
(-950 8650);
DISPLAY 0.680851 (-950 8650);
PAINT MONO (-950 8650);
DISPLAY INVISIBLE (-950 8650);
FORCEPROP 0 LAST CDS_SEC 1
J 0
(-950 8650);
DISPLAY 0.680851 (-950 8650);
DISPLAY INVISIBLE (-950 8650);
FORCEPROP 1 LASTPIN (-925 8575) $PN 1
J 2
(-930 8537);
DISPLAY 0.787234 (-930 8537);
PAINT MONO (-930 8537);
FORCEPROP 1 LASTPIN (-925 8375) $PN 2
J 2
(-930 8385);
DISPLAY 0.787234 (-930 8385);
PAINT MONO (-930 8385);
FORCEPROP 1 LAST PACK_TYPE 0402LF
J 2
(-965 8300);
DISPLAY 0.638298 (-965 8300);
PAINT SKYBLUE (-965 8300);
FORCEPROP 1 LAST TOLERANCE 5%
J 2
(-970 8500);
DISPLAY 0.638298 (-970 8500);
PAINT SKYBLUE (-970 8500);
FORCEPROP 1 LAST VALUE 4.7K
J 2
(-970 8550);
DISPLAY 0.638298 (-970 8550);
PAINT SKYBLUE (-970 8550);
FORCEPROP 1 LAST MATERIAL CHIP
J 2
(-965 8400);
DISPLAY 0.638298 (-965 8400);
PAINT SKYBLUE (-965 8400);
FORCEPROP 1 LAST WATTAGE 1/16W
J 2
(-965 8450);
DISPLAY 0.638298 (-965 8450);
PAINT SKYBLUE (-965 8450);
FORCEPROP 2 LAST CDS_LIB pure_quanta
J 0
(-925 8475);
DISPLAY INVISIBLE (-925 8475);
FORCEPROP 1 LAST PATH I61
J 2
(-975 8650);
DISPLAY 0.978723 (-975 8650);
PAINT WHITE (-975 8650);
DISPLAY INVISIBLE (-975 8650);
FORCEPROP 1 LAST PART_NUMBER CS24702JB10
J 2
(-965 8350);
DISPLAY 0.638298 (-965 8350);
PAINT SKYBLUE (-965 8350);
DISPLAY INVISIBLE (-965 8350);
FORCEADD UNIVERSAL_POWER..1
(-925 8825);
FORCEPROP 3 LASTPIN (-925 8775) SIG_NAME P3V3_AUX\g
J 0
(-915 8785);
DISPLAY 0.659574 (-915 8785);
PAINT MONO (-915 8785);
DISPLAY INVISIBLE (-915 8785);
FORCEPROP 1 LAST HDL_POWER P3V3_AUX
J 1
(-925 8875);
DISPLAY 0.872340 (-925 8875);
PAINT GREEN (-925 8875);
FORCEPROP 2 LAST CDS_LIB pure_quanta_power
J 0
(-925 8825);
DISPLAY INVISIBLE (-925 8825);
FORCEPROP 1 LAST PATH I62
J 0
(-875 8850);
DISPLAY 0.872340 (-875 8850);
PAINT AQUA (-875 8850);
DISPLAY INVISIBLE (-875 8850);
FORCEADD UNIVERSAL_GND..1
(75 7650);
FORCEPROP 3 LASTPIN (75 7700) SIG_NAME GND\g
J 0
(85 7710);
DISPLAY 0.659574 (85 7710);
PAINT MONO (85 7710);
DISPLAY INVISIBLE (85 7710);
FORCEPROP 2 LAST CDS_LIB pure_quanta_power
J 0
(75 7650);
DISPLAY INVISIBLE (75 7650);
FORCEPROP 1 LAST HDL_POWER GND
J 1
(100 7575);
DISPLAY 0.872340 (100 7575);
PAINT GREEN (100 7575);
DISPLAY INVISIBLE (100 7575);
FORCEPROP 1 LAST PATH I63
J 0
(150 7650);
DISPLAY 0.872340 (150 7650);
PAINT AQUA (150 7650);
DISPLAY INVISIBLE (150 7650);
FORCEADD Q_RES..1
(650 3750);
FORCEPROP 1 LAST LOCATION R3441
J 0
(450 3750);
DISPLAY 0.638298 (450 3750);
FORCEPROP 0 LAST $SEC 1
J 0
(600 3850);
DISPLAY 0.680851 (600 3850);
PAINT MONO (600 3850);
DISPLAY INVISIBLE (600 3850);
FORCEPROP 0 LAST CDS_SEC 1
J 0
(600 3850);
DISPLAY 1.021277 (600 3850);
DISPLAY INVISIBLE (600 3850);
FORCEPROP 1 LASTPIN (550 3750) $PN 1
J 0
(562 3762);
DISPLAY 0.787234 (562 3762);
PAINT MONO (562 3762);
FORCEPROP 1 LASTPIN (750 3750) $PN 2
J 0
(712 3762);
DISPLAY 0.787234 (712 3762);
PAINT MONO (712 3762);
FORCEPROP 1 LAST TOLERANCE 5%
J 0
(875 3750);
DISPLAY 0.638298 (875 3750);
FORCEPROP 1 LAST WATTAGE 1/16W
J 2
(1225 3750);
DISPLAY 0.638298 (1225 3750);
FORCEPROP 1 LAST MATERIAL CHIP
J 0
(950 3750);
DISPLAY 0.638298 (950 3750);
FORCEPROP 1 LAST VALUE 0
J 2
(850 3750);
DISPLAY 0.638298 (850 3750);
FORCEPROP 1 LAST PACK_TYPE 0402LF
J 0
(175 3750);
DISPLAY 0.638298 (175 3750);
FORCEPROP 2 LAST CDS_LIB pure_quanta
J 0
(650 3750);
DISPLAY INVISIBLE (650 3750);
FORCEPROP 1 LAST PATH I64
J 0
(600 3900);
DISPLAY 0.978723 (600 3900);
PAINT WHITE (600 3900);
DISPLAY INVISIBLE (600 3900);
FORCEPROP 1 LAST PART_NUMBER CS00002JB13
J 0
(525 3700);
DISPLAY 0.638298 (525 3700);
DISPLAY INVISIBLE (525 3700);
FORCEADD Q_RES..1
(650 3950);
FORCEPROP 1 LAST LOCATION R3440
J 0
(450 3950);
DISPLAY 0.638298 (450 3950);
FORCEPROP 0 LAST $SEC 1
J 0
(1250 4000);
DISPLAY 0.680851 (1250 4000);
PAINT MONO (1250 4000);
DISPLAY INVISIBLE (1250 4000);
FORCEPROP 0 LAST CDS_SEC 1
J 0
(1250 4000);
DISPLAY 1.021277 (1250 4000);
DISPLAY INVISIBLE (1250 4000);
FORCEPROP 1 LASTPIN (550 3950) $PN 1
J 0
(562 3962);
DISPLAY 0.787234 (562 3962);
PAINT MONO (562 3962);
FORCEPROP 1 LASTPIN (750 3950) $PN 2
J 0
(712 3962);
DISPLAY 0.787234 (712 3962);
PAINT MONO (712 3962);
FORCEPROP 1 LAST PACK_TYPE 0402LF
J 0
(175 3950);
DISPLAY 0.638298 (175 3950);
FORCEPROP 1 LAST MATERIAL EMPTY
J 0
(950 3950);
DISPLAY 0.638298 (950 3950);
PAINT RED (950 3950);
FORCEPROP 1 LAST VALUE 0
J 2
(850 3950);
DISPLAY 0.638298 (850 3950);
FORCEPROP 1 LAST TOLERANCE 5%
J 0
(875 3950);
DISPLAY 0.638298 (875 3950);
FORCEPROP 1 LAST WATTAGE 1/16W
J 2
(1250 3950);
DISPLAY 0.638298 (1250 3950);
FORCEPROP 2 LAST CDS_LIB pure_quanta
J 0
(650 3950);
DISPLAY INVISIBLE (650 3950);
FORCEPROP 1 LAST PATH I65
J 0
(600 4100);
DISPLAY 0.978723 (600 4100);
PAINT WHITE (600 4100);
DISPLAY INVISIBLE (600 4100);
FORCEPROP 1 LAST PART_NUMBER CS00002JB13
J 0
(525 3900);
DISPLAY 0.638298 (525 3900);
DISPLAY INVISIBLE (525 3900);
FORCEADD Q_RES..1
(650 3350);
FORCEPROP 1 LAST LOCATION R3443
J 0
(450 3350);
DISPLAY 0.638298 (450 3350);
FORCEPROP 0 LAST $SEC 1
J 0
(1225 3400);
DISPLAY 0.680851 (1225 3400);
PAINT MONO (1225 3400);
DISPLAY INVISIBLE (1225 3400);
FORCEPROP 0 LAST CDS_SEC 1
J 0
(1225 3400);
DISPLAY 0.680851 (1225 3400);
DISPLAY INVISIBLE (1225 3400);
FORCEPROP 1 LASTPIN (550 3350) $PN 1
J 0
(562 3362);
DISPLAY 0.787234 (562 3362);
PAINT MONO (562 3362);
FORCEPROP 1 LASTPIN (750 3350) $PN 2
J 0
(712 3362);
DISPLAY 0.787234 (712 3362);
PAINT MONO (712 3362);
FORCEPROP 1 LAST TOLERANCE 5%
J 0
(875 3350);
DISPLAY 0.638298 (875 3350);
FORCEPROP 1 LAST VALUE 0
J 2
(850 3350);
DISPLAY 0.638298 (850 3350);
FORCEPROP 1 LAST WATTAGE 1/16W
J 2
(1225 3350);
DISPLAY 0.638298 (1225 3350);
FORCEPROP 1 LAST MATERIAL CHIP
J 0
(950 3350);
DISPLAY 0.638298 (950 3350);
FORCEPROP 1 LAST PACK_TYPE 0402LF
J 0
(175 3350);
DISPLAY 0.638298 (175 3350);
FORCEPROP 2 LAST CDS_LIB pure_quanta
J 0
(650 3350);
DISPLAY INVISIBLE (650 3350);
FORCEPROP 1 LAST PATH I66
J 0
(600 3500);
DISPLAY 0.978723 (600 3500);
PAINT WHITE (600 3500);
DISPLAY INVISIBLE (600 3500);
FORCEPROP 1 LAST PART_NUMBER CS00002JB13
J 0
(525 3300);
DISPLAY 0.638298 (525 3300);
DISPLAY INVISIBLE (525 3300);
FORCEADD Q_RES..1
(650 3550);
FORCEPROP 1 LAST LOCATION R3442
J 0
(450 3550);
DISPLAY 0.638298 (450 3550);
FORCEPROP 0 LAST $SEC 1
J 0
(1225 3600);
DISPLAY 0.680851 (1225 3600);
PAINT MONO (1225 3600);
DISPLAY INVISIBLE (1225 3600);
FORCEPROP 0 LAST CDS_SEC 1
J 0
(1225 3600);
DISPLAY 0.680851 (1225 3600);
DISPLAY INVISIBLE (1225 3600);
FORCEPROP 1 LASTPIN (550 3550) $PN 1
J 0
(562 3562);
DISPLAY 0.787234 (562 3562);
PAINT MONO (562 3562);
FORCEPROP 1 LASTPIN (750 3550) $PN 2
J 0
(712 3562);
DISPLAY 0.787234 (712 3562);
PAINT MONO (712 3562);
FORCEPROP 1 LAST TOLERANCE 5%
J 0
(875 3550);
DISPLAY 0.638298 (875 3550);
FORCEPROP 1 LAST WATTAGE 1/16W
J 2
(1225 3550);
DISPLAY 0.638298 (1225 3550);
FORCEPROP 1 LAST MATERIAL CHIP
J 0
(950 3550);
DISPLAY 0.638298 (950 3550);
FORCEPROP 1 LAST VALUE 0
J 2
(850 3550);
DISPLAY 0.638298 (850 3550);
FORCEPROP 1 LAST PACK_TYPE 0402LF
J 0
(175 3550);
DISPLAY 0.638298 (175 3550);
FORCEPROP 2 LAST CDS_LIB pure_quanta
J 0
(650 3550);
DISPLAY INVISIBLE (650 3550);
FORCEPROP 1 LAST PATH I67
J 0
(600 3700);
DISPLAY 0.978723 (600 3700);
PAINT WHITE (600 3700);
DISPLAY INVISIBLE (600 3700);
FORCEPROP 1 LAST PART_NUMBER CS00002JB13
J 0
(525 3500);
DISPLAY 0.638298 (525 3500);
DISPLAY INVISIBLE (525 3500);
FORCEADD UNIVERSAL_GND..1
(1700 2925);
FORCEPROP 3 LASTPIN (1700 2975) SIG_NAME GND\g
J 0
(1710 2985);
DISPLAY 0.659574 (1710 2985);
PAINT MONO (1710 2985);
DISPLAY INVISIBLE (1710 2985);
FORCEPROP 2 LAST CDS_LIB pure_quanta_power
J 0
(1700 2925);
DISPLAY INVISIBLE (1700 2925);
FORCEPROP 1 LAST HDL_POWER GND
J 1
(1725 2850);
DISPLAY 0.872340 (1725 2850);
PAINT GREEN (1725 2850);
DISPLAY INVISIBLE (1725 2850);
FORCEPROP 1 LAST PATH I68
J 0
(1775 2925);
DISPLAY 0.872340 (1775 2925);
PAINT AQUA (1775 2925);
DISPLAY INVISIBLE (1775 2925);
FORCEADD Q_RES..1
(675 4175);
FORCEPROP 1 LAST LOCATION R2656
J 0
(450 4175);
DISPLAY 0.638298 (450 4175);
FORCEPROP 2 LAST $SEC 1
J 0
(625 4375);
DISPLAY 0.680851 (625 4375);
PAINT MONO (625 4375);
DISPLAY INVISIBLE (625 4375);
FORCEPROP 2 LAST CDS_SEC 1
J 0
(625 4375);
DISPLAY 1.021277 (625 4375);
DISPLAY INVISIBLE (625 4375);
FORCEPROP 1 LASTPIN (575 4175) $PN 1
J 0
(587 4187);
DISPLAY 0.787234 (587 4187);
FORCEPROP 1 LASTPIN (775 4175) $PN 2
J 0
(737 4187);
DISPLAY 0.787234 (737 4187);
FORCEPROP 1 LAST VALUE 100
J 2
(850 4175);
DISPLAY 0.510638 (850 4175);
FORCEPROP 1 LAST PACK_TYPE 0402LF
J 0
(700 4100);
DISPLAY 0.404255 (700 4100);
FORCEPROP 1 LAST WATTAGE 1/16W
J 2
(675 4100);
DISPLAY 0.404255 (675 4100);
FORCEPROP 1 LAST MATERIAL EMPTY
J 0
(750 4150);
DISPLAY 0.510638 (750 4150);
PAINT RED (750 4150);
FORCEPROP 1 LAST TOLERANCE 1%
J 0
(1250 3950);
DISPLAY 0.510638 (1250 3950);
FORCEPROP 2 LAST CDS_LIB pure_quanta
J 0
(675 4175);
PAINT MONO (675 4175);
DISPLAY INVISIBLE (675 4175);
FORCEPROP 1 LAST PATH I69
J 0
(625 4325);
DISPLAY 0.978723 (625 4325);
PAINT WHITE (625 4325);
DISPLAY INVISIBLE (625 4325);
FORCEPROP 1 LAST PART_NUMBER CS11002FB07
J 0
(575 4125);
DISPLAY 0.404255 (575 4125);
DISPLAY INVISIBLE (575 4125);
FORCEADD OFFPAGE..4
R 2
(-6875 6000);
FORCEPROP 2 LAST $XR0 116 
J 0
(-7127 6000);
DISPLAY 0.638298 (-7127 6000);
PAINT MONO (-7127 6000);
FORCEPROP 2 LAST CDS_LIB standard
J 0
(-6875 6000);
DISPLAY INVISIBLE (-6875 6000);
FORCEPROP 1 LAST OFFPAGE TRUE
J 2
(-7200 5875);
DISPLAY 0.872340 (-7200 5875);
PAINT GREEN (-7200 5875);
DISPLAY INVISIBLE (-7200 5875);
FORCEPROP 1 LAST COMMENT_BODY TRUE
J 2
(-6850 5900);
DISPLAY 0.872340 (-6850 5900);
PAINT GREEN (-6850 5900);
DISPLAY INVISIBLE (-6850 5900);
FORCEPROP 2 LAST PATH I7
J 0
(-7150 6050);
DISPLAY 0.680851 (-7150 6050);
DISPLAY INVISIBLE (-7150 6050);
FORCEADD UNIVERSAL_GND..1
(775 7750);
FORCEPROP 3 LASTPIN (775 7800) SIG_NAME GND\g
J 0
(785 7810);
DISPLAY 0.659574 (785 7810);
PAINT MONO (785 7810);
DISPLAY INVISIBLE (785 7810);
FORCEPROP 2 LAST CDS_LIB pure_quanta_power
J 0
(775 7750);
DISPLAY INVISIBLE (775 7750);
FORCEPROP 1 LAST HDL_POWER GND
J 1
(800 7675);
DISPLAY 0.872340 (800 7675);
PAINT GREEN (800 7675);
DISPLAY INVISIBLE (800 7675);
FORCEPROP 1 LAST PATH I70
J 0
(850 7750);
DISPLAY 0.872340 (850 7750);
PAINT AQUA (850 7750);
DISPLAY INVISIBLE (850 7750);
FORCEADD Q_CAP..1
(775 8125);
FORCEPROP 1 LAST LOCATION C9002
J 0
(825 8225);
DISPLAY 0.978723 (825 8225);
PAINT SKYBLUE (825 8225);
FORCEPROP 0 LAST $SEC 1
J 0
(825 8275);
DISPLAY 0.680851 (825 8275);
PAINT MONO (825 8275);
DISPLAY INVISIBLE (825 8275);
FORCEPROP 0 LAST CDS_SEC 1
J 0
(825 8275);
DISPLAY 0.680851 (825 8275);
DISPLAY INVISIBLE (825 8275);
FORCEPROP 1 LASTPIN (775 8225) $PN 1
J 0
(785 8205);
DISPLAY 0.787234 (785 8205);
PAINT MONO (785 8205);
FORCEPROP 1 LASTPIN (775 8025) $PN 2
J 0
(785 8005);
DISPLAY 0.787234 (785 8005);
PAINT MONO (785 8005);
FORCEPROP 1 LAST VALUE 1000PF
J 0
(825 8175);
DISPLAY 0.978723 (825 8175);
PAINT SKYBLUE (825 8175);
FORCEPROP 1 LAST TOLERANCE 5%
J 0
(825 8075);
DISPLAY 0.978723 (825 8075);
PAINT SKYBLUE (825 8075);
FORCEPROP 1 LAST MATERIAL EMPTY
J 0
(825 8025);
DISPLAY 0.978723 (825 8025);
PAINT SKYBLUE (825 8025);
FORCEPROP 1 LAST PACK_TYPE 0402
J 0
(825 7925);
DISPLAY 0.978723 (825 7925);
PAINT SKYBLUE (825 7925);
FORCEPROP 1 LAST VOLTAGE 50V
J 0
(825 8125);
DISPLAY 0.978723 (825 8125);
PAINT SKYBLUE (825 8125);
FORCEPROP 2 LAST CDS_LIB pure_quanta
J 0
(775 8125);
DISPLAY INVISIBLE (775 8125);
FORCEPROP 1 LAST PATH I71
J 0
(825 8275);
DISPLAY 0.978723 (825 8275);
PAINT WHITE (825 8275);
DISPLAY INVISIBLE (825 8275);
FORCEPROP 1 LAST PART_NUMBER TMP_QCH21006JB10
J 0
(825 7975);
DISPLAY 0.978723 (825 7975);
PAINT SKYBLUE (825 7975);
DISPLAY INVISIBLE (825 7975);
FORCEADD Q_RES..2
R 2
(75 8725);
FORCEPROP 1 LAST LOCATION R9017
J 2
(30 8850);
DISPLAY 0.978723 (30 8850);
PAINT SKYBLUE (30 8850);
FORCEPROP 0 LAST $SEC 1
J 0
(50 8900);
DISPLAY 0.680851 (50 8900);
PAINT MONO (50 8900);
DISPLAY INVISIBLE (50 8900);
FORCEPROP 0 LAST CDS_SEC 1
J 0
(50 8900);
DISPLAY 0.680851 (50 8900);
DISPLAY INVISIBLE (50 8900);
FORCEPROP 1 LASTPIN (75 8825) $PN 1
J 2
(70 8787);
DISPLAY 0.787234 (70 8787);
PAINT MONO (70 8787);
FORCEPROP 1 LASTPIN (75 8625) $PN 2
J 2
(70 8635);
DISPLAY 0.787234 (70 8635);
PAINT MONO (70 8635);
FORCEPROP 1 LAST PACK_TYPE 0402LF
J 2
(35 8550);
DISPLAY 0.638298 (35 8550);
PAINT SKYBLUE (35 8550);
FORCEPROP 1 LAST WATTAGE 1/16W
J 2
(35 8700);
DISPLAY 0.638298 (35 8700);
PAINT SKYBLUE (35 8700);
FORCEPROP 1 LAST TOLERANCE 5%
J 2
(30 8750);
DISPLAY 0.638298 (30 8750);
PAINT SKYBLUE (30 8750);
FORCEPROP 1 LAST VALUE 4.7K
J 2
(30 8800);
DISPLAY 0.638298 (30 8800);
PAINT SKYBLUE (30 8800);
FORCEPROP 1 LAST MATERIAL CHIP
J 2
(35 8650);
DISPLAY 0.638298 (35 8650);
PAINT SKYBLUE (35 8650);
FORCEPROP 2 LAST CDS_LIB pure_quanta
J 0
(75 8725);
DISPLAY INVISIBLE (75 8725);
FORCEPROP 1 LAST PATH I72
J 2
(25 8900);
DISPLAY 0.978723 (25 8900);
PAINT WHITE (25 8900);
DISPLAY INVISIBLE (25 8900);
FORCEPROP 1 LAST PART_NUMBER CS24702JB10
J 2
(35 8600);
DISPLAY 0.638298 (35 8600);
PAINT SKYBLUE (35 8600);
DISPLAY INVISIBLE (35 8600);
FORCEADD UNIVERSAL_POWER..1
(75 9000);
FORCEPROP 3 LASTPIN (75 8950) SIG_NAME P3V3_AUX\g
J 0
(85 8960);
DISPLAY 0.659574 (85 8960);
PAINT MONO (85 8960);
DISPLAY INVISIBLE (85 8960);
FORCEPROP 1 LAST HDL_POWER P3V3_AUX
J 1
(75 9050);
DISPLAY 0.872340 (75 9050);
PAINT GREEN (75 9050);
FORCEPROP 2 LAST CDS_LIB pure_quanta_power
J 0
(75 9000);
DISPLAY INVISIBLE (75 9000);
FORCEPROP 1 LAST PATH I73
J 0
(125 9025);
DISPLAY 0.872340 (125 9025);
PAINT AQUA (125 9025);
DISPLAY INVISIBLE (125 9025);
FORCEADD OFFPAGE..2
(1125 8475);
FORCEPROP 2 LAST $XR0 246 
J 0
(1314 8475);
DISPLAY 0.638298 (1314 8475);
PAINT MONO (1314 8475);
FORCEPROP 2 LAST CDS_LIB standard
J 0
(1125 8475);
DISPLAY INVISIBLE (1125 8475);
FORCEPROP 1 LAST OFFPAGE TRUE
J 0
(1450 8350);
DISPLAY 0.872340 (1450 8350);
PAINT AQUA (1450 8350);
DISPLAY INVISIBLE (1450 8350);
FORCEPROP 1 LAST COMMENT_BODY TRUE
J 0
(1080 8380);
DISPLAY 0.872340 (1080 8380);
PAINT GREEN (1080 8380);
DISPLAY INVISIBLE (1080 8380);
FORCEPROP 2 LAST PATH I74
J 0
(1325 8525);
DISPLAY 0.680851 (1325 8525);
DISPLAY INVISIBLE (1325 8525);
FORCEADD MOSFET_NCH_DUAL..2
(25 8175);
FORCEPROP 1 LAST LOCATION Q9002
J 0
(176 8151);
DISPLAY 0.723404 (176 8151);
PAINT SKYBLUE (176 8151);
FORCEPROP 0 LAST $SEC 2
J 0
(200 8300);
DISPLAY 0.680851 (200 8300);
PAINT MONO (200 8300);
DISPLAY INVISIBLE (200 8300);
FORCEPROP 0 LAST CDS_SEC 2
J 0
(200 8300);
DISPLAY 0.680851 (200 8300);
DISPLAY INVISIBLE (200 8300);
FORCEPROP 0 LASTPIN (75 8375) $PN 3
R 1
J 0
(65 8385);
DISPLAY 0.680851 (65 8385);
PAINT MONO (65 8385);
FORCEPROP 0 LASTPIN (-175 8125) $PN 5
J 2
(-185 8135);
DISPLAY 0.680851 (-185 8135);
PAINT MONO (-185 8135);
FORCEPROP 0 LASTPIN (75 7975) $PN 4
R 1
J 2
(65 7965);
DISPLAY 0.680851 (65 7965);
PAINT MONO (65 7965);
FORCEPROP 2 LAST PART_TYPE SMLF
J 0
(200 8250);
DISPLAY 0.680851 (200 8250);
PAINT SKYBLUE (200 8250);
FORCEPROP 2 LAST VALUE PJT138K
J 0
(200 8200);
DISPLAY 0.680851 (200 8200);
PAINT SKYBLUE (200 8200);
FORCEPROP 1 LAST MATERIAL IC
J 0
(176 8026);
DISPLAY 0.723404 (176 8026);
PAINT SKYBLUE (176 8026);
FORCEPROP 1 LAST NEEDS_NO_SIZE TRUE
J 0
(175 8066);
DISPLAY 0.468085 (175 8066);
PAINT GREEN (175 8066);
DISPLAY INVISIBLE (175 8066);
FORCEPROP 1 LAST CDS_LMAN_SYM_OUTLINE -150,150,150,-150
J 0
(25 8175);
DISPLAY 0.468085 (25 8175);
PAINT GREEN (25 8175);
DISPLAY INVISIBLE (25 8175);
FORCEPROP 2 LAST CDS_LIB pure_quanta
J 0
(25 8175);
DISPLAY INVISIBLE (25 8175);
FORCEPROP 1 LAST PATH I75
J 0
(175 8025);
DISPLAY 0.723404 (175 8025);
PAINT GREEN (175 8025);
DISPLAY INVISIBLE (175 8025);
FORCEPROP 1 LAST PART_NUMBER BAM138K0003
J 0
(176 8081);
DISPLAY 0.723404 (176 8081);
PAINT SKYBLUE (176 8081);
DISPLAY INVISIBLE (176 8081);
FORCEADD Q_RES..2
R 2
(-6100 6375);
FORCEPROP 1 LAST LOCATION R9002
J 2
(-6145 6500);
DISPLAY 0.808511 (-6145 6500);
FORCEPROP 2 LAST SEC 1
J 0
(-6150 6600);
DISPLAY 0.680851 (-6150 6600);
PAINT MONO (-6150 6600);
DISPLAY INVISIBLE (-6150 6600);
FORCEPROP 1 LASTPIN (-6100 6475) $PN 1
J 2
(-6105 6437);
DISPLAY 0.787234 (-6105 6437);
PAINT MONO (-6105 6437);
FORCEPROP 1 LASTPIN (-6100 6275) $PN 2
J 2
(-6105 6285);
DISPLAY 0.787234 (-6105 6285);
PAINT MONO (-6105 6285);
FORCEPROP 1 LAST PACK_TYPE 0402LF
J 2
(-6140 6200);
DISPLAY 0.638298 (-6140 6200);
FORCEPROP 1 LAST VALUE 10K
J 2
(-6145 6450);
DISPLAY 0.638298 (-6145 6450);
FORCEPROP 1 LAST WATTAGE 1/16W
J 2
(-6140 6350);
DISPLAY 0.638298 (-6140 6350);
FORCEPROP 1 LAST MATERIAL CHIP
J 2
(-6140 6300);
DISPLAY 0.638298 (-6140 6300);
FORCEPROP 1 LAST TOLERANCE 1%
J 2
(-6145 6400);
DISPLAY 0.638298 (-6145 6400);
FORCEPROP 2 LAST SEC_TYPE 0402LF
J 0
(-6150 6600);
DISPLAY 0.680851 (-6150 6600);
DISPLAY INVISIBLE (-6150 6600);
FORCEPROP 2 LAST CDS_LIB pure_quanta
J 2
(-6100 6375);
DISPLAY INVISIBLE (-6100 6375);
FORCEPROP 1 LAST PATH I8
J 2
(-6150 6550);
DISPLAY 0.978723 (-6150 6550);
PAINT WHITE (-6150 6550);
DISPLAY INVISIBLE (-6150 6550);
FORCEPROP 1 LAST PART_NUMBER CS31002FB08
J 2
(-6140 6250);
DISPLAY 0.638298 (-6140 6250);
DISPLAY INVISIBLE (-6140 6250);
FORCEADD UNIVERSAL_POWER..1
(-6100 6675);
FORCEPROP 3 LASTPIN (-6100 6625) SIG_NAME P3V3_AUX\g
J 0
(-6090 6635);
DISPLAY 0.659574 (-6090 6635);
PAINT MONO (-6090 6635);
DISPLAY INVISIBLE (-6090 6635);
FORCEPROP 1 LAST HDL_POWER P3V3_AUX
J 1
(-6100 6725);
DISPLAY 0.872340 (-6100 6725);
PAINT GREEN (-6100 6725);
FORCEPROP 2 LAST CDS_LIB pure_quanta_power
J 0
(-6100 6675);
DISPLAY INVISIBLE (-6100 6675);
FORCEPROP 1 LAST PATH I9
J 0
(-6050 6700);
DISPLAY 0.872340 (-6050 6700);
PAINT AQUA (-6050 6700);
DISPLAY INVISIBLE (-6050 6700);
FORCEADD QUANTA_TITLE_BLOCK_C..1
(2025 2525);
FORCEPROP 0 LAST CDS_CON_LAST_MODIFIED Thu Sep 14 16:12:23 2023
J 0
(140 2540);
DISPLAY INVISIBLE (140 2540);
FORCEPROP 1 LAST CUSTOM_TXT_CDS <CON_LAST_MODIFIED>
J 0
(140 2540);
DISPLAY 0.978723 (140 2540);
FORCEPROP 2 LAST CUSTOM_TXT_CDS <XR_PAGE_TITLE>
J 0
(-5865 7775);
DISPLAY 0.638298 (-5865 7775);
PAINT PINK (-5865 7775);
DISPLAY INVISIBLE (-5865 7775);
FORCEPROP 1 LAST CUSTOM_TXT_CDS <NAME_2>
J 0
(-1150 2575);
FORCEPROP 1 LAST CUSTOM_TXT_CDS <NAME_1>
J 0
(-1150 2700);
FORCEPROP 1 LAST CUSTOM_TXT_CDS <Q_NUMBER>
J 0
(622 2628);
DISPLAY 1.212766 (622 2628);
FORCEPROP 1 LAST CUSTOM_TXT_CDS <Q_PROJ>
J 0
(-357 2627);
DISPLAY 1.212766 (-357 2627);
FORCEPROP 1 LAST CUSTOM_TXT_CDS <Q_REV>
J 0
(1841 2628);
DISPLAY 1.212766 (1841 2628);
FORCEPROP 1 LAST CUSTOM_TXT_CDS <CON_PAGE_NUM> OF <CON_TOTAL_PAGES>
J 0
(1579 2543);
DISPLAY 0.978723 (1579 2543);
FORCEPROP 1 LAST Q_TITLE EXAMAX_PRESENT
J 0
(-7341 2551);
DISPLAY 2.446809 (-7341 2551);
PAINT GREEN (-7341 2551);
FORCEPROP 2 LAST CDS_LIB pure_quanta
J 0
(2025 2525);
DISPLAY INVISIBLE (2025 2525);
FORCEPROP 1 LAST CDS_LMAN_SYM_OUTLINE -9475,6775,100,-125
J 0
(2025 2525);
DISPLAY 0.468085 (2025 2525);
PAINT GREEN (2025 2525);
DISPLAY INVISIBLE (2025 2525);
FORCEPROP 2 LAST PAGE_BORDER TRUE
J 0
(-5865 7775);
DISPLAY 0.638298 (-5865 7775);
PAINT PINK (-5865 7775);
DISPLAY INVISIBLE (-5865 7775);
FORCEPROP 2 LAST CDS_XR_PAGE_TITLE CR-123 : @T6G_MB_LIB.T6G(SCH_1):PAGE123
J 0
(-5865 7775);
DISPLAY 0.638298 (-5865 7775);
PAINT PINK (-5865 7775);
DISPLAY INVISIBLE (-5865 7775);
FORCEPROP 1 LAST Q_DEPT BU9
J 1
(-1738 2574);
DISPLAY 1.957447 (-1738 2574);
PAINT GREEN (-1738 2574);
DISPLAY INVISIBLE (-1738 2574);
FORCEPROP 1 LAST COMMENT_BODY TRUE
J 0
(2037 2512);
DISPLAY 0.978723 (2037 2512);
PAINT GREEN (2037 2512);
DISPLAY INVISIBLE (2037 2512);
FORCEADD DNS..2
(875 8125);
PAINT RED (875 8125);
FORCEPROP 2 LAST CDS_LIB mstr_misc
J 0
(875 8125);
DISPLAY INVISIBLE (875 8125);
FORCEPROP 1 LAST COMMENT_BODY TRUE
J 0
(875 8125);
DISPLAY INVISIBLE (875 8125);
FORCEADD DNS..2
(675 4200);
PAINT RED (675 4200);
FORCEPROP 2 LAST CDS_LIB mstr_misc
J 0
(675 4200);
DISPLAY INVISIBLE (675 4200);
FORCEPROP 1 LAST COMMENT_BODY TRUE
J 0
(675 4200);
DISPLAY INVISIBLE (675 4200);
FORCEADD DNS..2
(675 3950);
PAINT RED (675 3950);
FORCEPROP 2 LAST CDS_LIB mstr_misc
J 0
(675 3950);
DISPLAY INVISIBLE (675 3950);
FORCEPROP 1 LAST COMMENT_BODY TRUE
J 0
(675 3950);
DISPLAY INVISIBLE (675 3950);
FORCEADD DNS..2
(-1250 7525);
PAINT RED (-1250 7525);
FORCEPROP 2 LAST CDS_LIB mstr_misc
J 0
(-1250 7525);
DISPLAY INVISIBLE (-1250 7525);
FORCEPROP 1 LAST COMMENT_BODY TRUE
J 0
(-1250 7525);
DISPLAY INVISIBLE (-1250 7525);
FORCEADD DNS..2
(-3900 6350);
PAINT RED (-3900 6350);
FORCEPROP 2 LAST CDS_LIB mstr_misc
J 0
(-3900 6350);
DISPLAY INVISIBLE (-3900 6350);
FORCEPROP 1 LAST COMMENT_BODY TRUE
J 0
(-3900 6350);
DISPLAY INVISIBLE (-3900 6350);
FORCEADD DNS..2
(-3850 4550);
PAINT RED (-3850 4550);
FORCEPROP 2 LAST CDS_LIB mstr_misc
J 0
(-3850 4550);
DISPLAY INVISIBLE (-3850 4550);
FORCEPROP 1 LAST COMMENT_BODY TRUE
J 0
(-3850 4550);
DISPLAY INVISIBLE (-3850 4550);
FORCEADD DNS..2
(-4050 8125);
PAINT RED (-4050 8125);
FORCEPROP 2 LAST CDS_LIB mstr_misc
J 0
(-4050 8125);
DISPLAY INVISIBLE (-4050 8125);
FORCEPROP 1 LAST COMMENT_BODY TRUE
J 0
(-4050 8125);
DISPLAY INVISIBLE (-4050 8125);
FORCEADD DNS..2
(-6225 7525);
PAINT RED (-6225 7525);
FORCEPROP 2 LAST CDS_LIB mstr_misc
J 0
(-6225 7525);
DISPLAY INVISIBLE (-6225 7525);
FORCEPROP 1 LAST COMMENT_BODY TRUE
J 0
(-6225 7525);
DISPLAY INVISIBLE (-6225 7525);
FORCEADD DNS..2
(-6025 5750);
PAINT RED (-6025 5750);
FORCEPROP 2 LAST CDS_LIB mstr_misc
J 0
(-6025 5750);
DISPLAY INVISIBLE (-6025 5750);
FORCEPROP 1 LAST COMMENT_BODY TRUE
J 0
(-6025 5750);
DISPLAY INVISIBLE (-6025 5750);
FORCEADD DNS..2
(-5975 3950);
PAINT RED (-5975 3950);
FORCEPROP 2 LAST CDS_LIB mstr_misc
J 0
(-5975 3950);
DISPLAY INVISIBLE (-5975 3950);
FORCEPROP 1 LAST COMMENT_BODY TRUE
J 0
(-5975 3950);
DISPLAY INVISIBLE (-5975 3950);
WIRE 16 -1 (-6025 3850)(-6025 3675);
WIRE 16 -1 (-6275 7425)(-6275 7250);
WIRE 16 -1 (-6075 5650)(-6075 5475);
WIRE 16 -1 (-6050 4675)(-6050 4825);
WIRE 16 -1 (-5650 5000)(-5650 5200);
WIRE 16 -1 (-5700 5850)(-5700 5550);
WIRE 16 -1 (-4650 5250)(-4650 5375);
WIRE 16 -1 (-4700 6200)(-4700 5925);
WIRE 16 -1 (-5700 6800)(-5700 7000);
WIRE 16 -1 (-5675 7625)(-5675 7325);
WIRE 16 -1 (-4850 7975)(-4850 7700);
WIRE 16 -1 (-4700 7050)(-4700 7175);
WIRE 16 -1 (-4150 8025)(-4150 7800);
WIRE 16 -1 (-5650 4050)(-5650 3750);
WIRE 16 -1 (-3950 4450)(-3950 4225);
WIRE 16 -1 (-4000 6250)(-4000 6025);
WIRE 16 -1 (-1300 7425)(-1300 7250);
WIRE 16 -1 (-4650 4400)(-4650 4125);
WIRE 16 -1 (-925 7625)(-925 7325);
WIRE 16 -1 (-6300 8250)(-6300 8400);
WIRE 16 -1 (-5675 8575)(-5675 8775);
WIRE 16 -1 (-4850 8825)(-4850 8950);
WIRE 16 -1 (-1325 8250)(-1325 8400);
WIRE 16 -1 (-925 8575)(-925 8775);
WIRE 16 -1 (75 7975)(75 7700);
WIRE 16 -1 (775 8025)(775 7800);
WIRE 16 -1 (75 8825)(75 8950);
WIRE 16 -1 (-6100 6475)(-6100 6625);
WIRE 16 -1 (75 8375)(75 8475);
WIRE 16 -1 (75 8475)(775 8475);
FORCEPROP 2 LAST SIG_NAME PRSNT_CABLE_GPU_A3_ISO_N
J 0
(190 8485);
DISPLAY 0.680851 (190 8485);
WIRE 16 -1 (75 8625)(75 8475);
WIRE 16 -1 (775 8475)(1075 8475);
WIRE 16 -1 (775 8225)(775 8475);
WIRE 16 -1 (1700 3350)(1700 3550);
WIRE 16 -1 (1700 2975)(1700 3350);
WIRE 16 -1 (1700 3350)(750 3350);
WIRE 16 -1 (1700 3550)(1700 3750);
WIRE 16 -1 (1700 3550)(750 3550);
WIRE 16 -1 (1700 3750)(1700 3950);
WIRE 16 -1 (1700 3750)(750 3750);
WIRE 16 -1 (1700 3950)(1700 4175);
WIRE 16 -1 (1700 3950)(750 3950);
WIRE 16 -1 (1700 4175)(775 4175);
WIRE 16 -1 (550 3950)(-500 3950);
FORCEPROP 2 LAST SIG_NAME GPU_BASE_ID0
J 0
(-460 3960);
DISPLAY 0.638298 (-460 3960);
WIRE 16 -1 (550 3750)(-500 3750);
FORCEPROP 2 LAST SIG_NAME GPU_BASE_ID1
J 0
(-460 3760);
DISPLAY 0.638298 (-460 3760);
WIRE 16 -1 (550 3350)(-500 3350);
FORCEPROP 2 LAST SIG_NAME GPU_PEX_STRAP1
J 0
(-460 3360);
DISPLAY 0.638298 (-460 3360);
WIRE 16 -1 (550 3550)(-500 3550);
FORCEPROP 2 LAST SIG_NAME GPU_PEX_STRAP0
J 0
(-460 3560);
DISPLAY 0.638298 (-460 3560);
WIRE 16 -1 (575 4175)(-500 4175);
FORCEPROP 2 LAST SIG_NAME HGX_DETECT_N_ISO
J 0
(-460 4185);
DISPLAY 0.638298 (-460 4185);
WIRE 16 -1 (-4850 8375)(-4850 8475);
WIRE 16 -1 (-4850 8475)(-4150 8475);
FORCEPROP 2 LAST SIG_NAME PRSNT_SWB_ISO_N
J 0
(-4610 8485);
DISPLAY 0.680851 (-4610 8485);
PAINT SKYBLUE (-4610 8485);
WIRE 16 -1 (-4850 8625)(-4850 8475);
WIRE 16 -1 (-4150 8475)(-3850 8475);
WIRE 16 -1 (-4150 8225)(-4150 8475);
WIRE 16 -1 (-925 8025)(-925 8125);
WIRE 16 -1 (-925 8125)(-925 8375);
WIRE 16 -1 (-175 8125)(-925 8125);
FORCEPROP 2 LAST SIG_NAME PRSNT_CABLE_GPU_A3
J 0
(-785 8160);
DISPLAY 0.680851 (-785 8160);
FORCEPROP 2 LASTPROP $XRERR UNIQUE?
J 0
(-1025 8160);
DISPLAY 0.638298 (-1025 8160);
PAINT MONO (-1025 8160);
DISPLAY INVISIBLE (-1025 8160);
WIRE 16 -1 (-1325 8050)(-1325 7775);
WIRE 16 -1 (-1300 7775)(-1325 7775);
WIRE 16 -1 (-1325 7775)(-2050 7775);
FORCEPROP 2 LAST SIG_NAME PRSNT_CABLE_GPU_A3_N
J 0
(-2010 7810);
DISPLAY 0.680851 (-2010 7810);
WIRE 16 -1 (-1175 7775)(-1300 7775);
WIRE 16 -1 (-1300 7625)(-1300 7775);
WIRE 16 -1 (-4650 4800)(-4650 4900);
WIRE 16 -1 (-4650 4900)(-3950 4900);
FORCEPROP 2 LAST SIG_NAME PRSNT_CABLE_SWB_B2_ISO_N
J 0
(-4535 4910);
DISPLAY 0.680851 (-4535 4910);
WIRE 16 -1 (-4650 5050)(-4650 4900);
WIRE 16 -1 (-3950 4900)(-3650 4900);
WIRE 16 -1 (-3950 4650)(-3950 4900);
WIRE 16 -1 (-4700 6600)(-4700 6700);
WIRE 16 -1 (-4700 6700)(-4000 6700);
FORCEPROP 2 LAST SIG_NAME PRSNT_CABLE_SWB_B1_ISO_N
J 0
(-4460 6710);
DISPLAY 0.680851 (-4460 6710);
PAINT SKYBLUE (-4460 6710);
WIRE 16 -1 (-4700 6850)(-4700 6700);
WIRE 16 -1 (-4000 6700)(-3700 6700);
WIRE 16 -1 (-4000 6450)(-4000 6700);
WIRE 16 -1 (-5675 8025)(-5675 8125);
WIRE 16 -1 (-5675 8125)(-5675 8375);
WIRE 16 -1 (-5100 8125)(-5675 8125);
FORCEPROP 2 LAST SIG_NAME PRSNT_SWB
J 0
(-5510 8135);
DISPLAY 0.680851 (-5510 8135);
PAINT SKYBLUE (-5510 8135);
FORCEPROP 2 LASTPROP $XRERR UNIQUE?
J 0
(-5750 8135);
DISPLAY 0.638298 (-5750 8135);
PAINT MONO (-5750 8135);
DISPLAY INVISIBLE (-5750 8135);
WIRE 16 -1 (-4950 6350)(-5700 6350);
FORCEPROP 2 LAST SIG_NAME PRSNT_CABLE_SWB_B1
J 0
(-5635 6375);
DISPLAY 0.680851 (-5635 6375);
PAINT SKYBLUE (-5635 6375);
FORCEPROP 2 LASTPROP $XRERR UNIQUE?
J 0
(-5875 6375);
DISPLAY 0.638298 (-5875 6375);
PAINT MONO (-5875 6375);
DISPLAY INVISIBLE (-5875 6375);
WIRE 16 -1 (-5700 6350)(-5700 6600);
WIRE 16 -1 (-5700 6250)(-5700 6350);
WIRE 16 -1 (-5650 4450)(-5650 4550);
WIRE 16 -1 (-4900 4550)(-5650 4550);
FORCEPROP 2 LAST SIG_NAME PRSNT_CABLE_SWB_B2
J 0
(-5510 4585);
DISPLAY 0.680851 (-5510 4585);
FORCEPROP 2 LASTPROP $XRERR UNIQUE?
J 0
(-5750 4585);
DISPLAY 0.638298 (-5750 4585);
PAINT MONO (-5750 4585);
DISPLAY INVISIBLE (-5750 4585);
WIRE 16 -1 (-5650 4550)(-5650 4800);
WIRE 16 -1 (-6025 4050)(-6025 4200);
WIRE 16 -1 (-5900 4200)(-6025 4200);
WIRE 16 -1 (-6025 4200)(-6050 4200);
WIRE 16 -1 (-6050 4475)(-6050 4200);
WIRE 16 -1 (-6050 4200)(-6775 4200);
FORCEPROP 2 LAST SIG_NAME PRSNT_CABLE_SWB_B2_N
J 0
(-6735 4235);
DISPLAY 0.680851 (-6735 4235);
WIRE 16 -1 (-6100 6275)(-6100 6000);
WIRE 16 -1 (-6075 6000)(-6100 6000);
WIRE 16 -1 (-6100 6000)(-6825 6000);
FORCEPROP 2 LAST SIG_NAME PRSNT_CABLE_SWB_B1_N
J 0
(-6760 6010);
DISPLAY 0.638298 (-6760 6010);
WIRE 16 -1 (-5950 6000)(-6075 6000);
WIRE 16 -1 (-6075 5850)(-6075 6000);
WIRE 16 -1 (-6300 8050)(-6300 7775);
WIRE 16 -1 (-6275 7775)(-6300 7775);
WIRE 16 -1 (-6300 7775)(-6800 7775);
FORCEPROP 2 LAST SIG_NAME PRSNT_SWB_N
J 0
(-6735 7785);
DISPLAY 0.638298 (-6735 7785);
WIRE 16 -1 (-5925 7775)(-6275 7775);
WIRE 16 -1 (-6275 7625)(-6275 7775);
DOT 1 (775 8475);
DOT 1 (75 8475);
DOT 1 (1700 3750);
DOT 1 (1700 3950);
DOT 1 (1700 3350);
DOT 1 (1700 3550);
DOT 1 (-4150 8475);
DOT 1 (-4850 8475);
DOT 1 (-925 8125);
DOT 1 (-1325 7775);
DOT 1 (-1300 7775);
DOT 1 (-4000 6700);
DOT 1 (-3950 4900);
DOT 1 (-4700 6700);
DOT 1 (-5675 8125);
DOT 1 (-5700 6350);
DOT 1 (-4650 4900);
DOT 1 (-6075 6000);
DOT 1 (-5650 4550);
DOT 1 (-6050 4200);
DOT 1 (-6025 4200);
DOT 1 (-6275 7775);
DOT 1 (-6300 7775);
DOT 1 (-6100 6000);
QUIT
